STUFF LIST - 1  
10M02SCU169C8G-10M02SCU169C8G,A AJ10M020T00              U25             

----------------

74HC1G126GW-74HC1G126GW,SMLF,IA AL1G0126007              U26             
74HC1G126GW-74HC1G126GW,SMLF,IA AL1G0126007              U29             
74HC1G126GW-74HC1G126GW,SMLF,IA AL1G0126007              U33             
74HC1G126GW-74HC1G126GW,SMLF,IA AL1G0126007              U36             

----------------

74LVC1G07GW-74LVC1G07GW,SMLF,IA ALVC1G07002              U31             

----------------

74LVC1G17GW-74LVC1G17GW,SMLF,IA AL1G0017K01              U32             

----------------

AP22811AW57-AP22811AW5-7,SMLF,A AL022811000              U14             

----------------

AST2600A1GP-AST2600A1-GP,SMLF,A AJ026000T04              U5              

----------------

BAT54C-BAT54C,SMLF,IC,BCBAT54CA BCBAT54CZ04              U11             

----------------

BCM54612EB1KMLG-BCM54612EB1KMLA AL054612B00              U7              

----------------

BZA462A-BZA462A,SMLF,IC,BCZA46A BCZA462AZ01              D10             
BZA462A-BZA462A,SMLF,IC,BCZA46A BCZA462AZ01              D12             

----------------

CONN3_210P9103GBR1-CONN3_210-PA DFHD03MS212              J6              

----------------

CONN7_4400547-CONN7_440054-7,TA DFHD07MS405              J7              

----------------

CONN9_GSB311131HR-CONN9_GSB311A DFHS09FR401              J2              

----------------

DELTA_L-DELTA-L,THLF,EMPTY,TP24 TP24                     J9              
DELTA_L-DELTA-L,THLF,EMPTY,TP24 TP24                     J11             
DELTA_L-DELTA-L,THLF,EMPTY,TP24 TP24                     J12             
DELTA_L-DELTA-L,THLF,EMPTY,TP24 TP24                     J16             
DELTA_L-DELTA-L,THLF,EMPTY,TP24 TP24                     J17             
DELTA_L-DELTA-L,THLF,EMPTY,TP24 TP24                     J19             
DELTA_L-DELTA-L,THLF,EMPTY,TP24 TP24                     J20             
DELTA_L-DELTA-L,THLF,EMPTY,TP24 TP24                     J22             
DELTA_L-DELTA-L,THLF,EMPTY,TP24 TP24                     J23             
DELTA_L-DELTA-L,THLF,EMPTY,TP24 TP24                     J24             
DELTA_L-DELTA-L,THLF,EMPTY,TP24 TP24                     J25             
DELTA_L-DELTA-L,THLF,EMPTY,TP24 TP24                     J26             
DELTA_L-DELTA-L,THLF,EMPTY,TP24 TP24                     J27             
DELTA_L-DELTA-L,THLF,EMPTY,TP24 TP24                     J28             
DELTA_L-DELTA-L,THLF,EMPTY,TP24 TP24                     J29             
DELTA_L-DELTA-L,THLF,EMPTY,TP24 TP24                     J30             

----------------

DUMMY_SYMBOL-BMC_FLASH,MECH,MEA DUMMY8                   DM2             
DUMMY_SYMBOL-BMC_FLASH,MECH,MEA DUMMY8                   DM5             

----------------

DUMMY_SYMBOL-PB-E1_SMALL,MECH,A DUMMY3                   DM7             

----------------

DUMMY_SYMBOL-PCBA_LABEL_15X5,MA DUMMY4                   DM10            

----------------

DUMMY_SYMBOL-QUANTA_LOGO_7X26,A DUMMY1                   DM19            

----------------

DUMMY_SYMBOL-WEEE,MECH,EMPTY,DA DUMMY2                   DM4             

----------------

FCONN168_ME1016810106011-FCONNA GOLD195                  GF1             

----------------

FT234XDR-FT234XD-R,SMLF,IC,AL0A AL000234001              U17             

----------------

HOLE_TH-EMPTY,DUMMY50 DUMMY50                  H2B1            
HOLE_TH-EMPTY,DUMMY50 DUMMY50                  H2B2            

----------------

HOLE_TH-EMPTY,HOLE620 HOLE620                  H1              
HOLE_TH-EMPTY,HOLE620 HOLE620                  H2              

----------------

HOLE_TH-EMPTY,HOLE1101 HOLE1101                 H6              
HOLE_TH-EMPTY,HOLE1101 HOLE1101                 H7              

----------------

HOLE_TH-EMPTY,HOLE1211 HOLE1211                 H5              
HOLE_TH-EMPTY,HOLE1211 HOLE1211                 H9              

----------------

IDTQS3VH257PAG_SMLF-IDTQS3VH25A AL000257K00              U21             
IDTQS3VH257PAG_SMLF-IDTQS3VH25A AL000257K00              U30             

----------------

K4A8G165WCBCTD-K4A8G165WC-BCTDA AKD5FGUT502              U1              

----------------

M24128BWDW6TP-M24128-BWDW6TP,SA AKE30Z0K610              U19             

----------------

MMBT39047F-MMBT3904-7-F,SMLF,IA BA0390400H0              Q1              
MMBT39047F-MMBT3904-7-F,SMLF,IA BA0390400H0              Q3              

----------------

MOSFET_DUAL_6P-2N7002KDW,SMLF,A BAM70020047              Q12             

----------------

MOSFET_DUAL_6P-DMN2400UV-7,SMLA BAM24000000              Q8              

----------------

MOSFET_NCH_DUAL-2N7002KDW,SMLFA BAM70020047              Q2              

----------------

MOSFET_N_123-BSS123-7-F,SMLF,IA BAM01230014              Q7              

----------------

MOSFET_N_GSD-DMG6968U-7,SMLF,IA BAM69680000              Q9              
MOSFET_N_GSD-DMG6968U-7,SMLF,IA BAM69680000              Q10             

----------------

MOSFET_N_GSD-NX7002AK,SMLF,IC,A BAM70020062              Q11             

----------------

MOSFET_N_SMLF-BSS138K,BSS138K,A BAM138K0000              U12             

----------------

MPQ8626GDZ-MPQ8626GD-Z,SMLF,ICA AL008626000              PU1             

----------------

MPQ8633AGLEC807Z-MPQ8633AGLE-CA AL008633007              PU38            

----------------

MTFC8GAKAJCN1MWT-MTFC8GAKAJCN-A AKE3QZPTL02              U20             

----------------

MX66L1G45GMI08G-MX66L1G45GMI-0A AKE3LF-0Z00              U28             

----------------

NB695GDZ-NB695GD-Z,SMLF,IC,AL0A AL000695001              PU41            
NB695GDZ-NB695GD-Z,SMLF,IC,AL0A AL000695001              PU42            

----------------

OSC4_7X25000018-25MHZ,SMLF,MISA BF625000023              OSC1            
OSC4_7X25000018-25MHZ,SMLF,MISA BF625000023              OSC2            

----------------

PCA9517ADP_SMLF-PCA9517ADP,IC,A AL009517K00              D13             

----------------

PRTR5V0U2X-PRTR5V0U2X,SMLF,IC,A AL5V0U2X000              U38             

----------------

Q_CAP_0402-0.1UF,10V,10%,EMPTYA CH4102K1B03              C11             
Q_CAP_0402-0.1UF,10V,10%,EMPTYA CH4102K1B03              C226            
Q_CAP_0402-0.1UF,10V,10%,EMPTYA CH4102K1B03              C227            
Q_CAP_0402-0.1UF,10V,10%,EMPTYA CH4102K1B03              C228            
Q_CAP_0402-0.1UF,10V,10%,EMPTYA CH4102K1B03              C233            
Q_CAP_0402-0.1UF,10V,10%,EMPTYA CH4102K1B03              C235            

----------------

Q_CAP_0402-0.1UF,10V,10%,X7R,TA CH4102K1B03              C241            
Q_CAP_0402-0.1UF,10V,10%,X7R,TA CH4102K1B03              C265            
Q_CAP_0402-0.1UF,10V,10%,X7R,TA CH4102K1B03              C288            
Q_CAP_0402-0.1UF,10V,10%,X7R,TA CH4102K1B03              C293            
Q_CAP_0402-0.1UF,10V,10%,X7R,TA CH4102K1B03              C297            
Q_CAP_0402-0.1UF,10V,10%,X7R,TA CH4102K1B03              C301            
Q_CAP_0402-0.1UF,10V,10%,X7R,TA CH4102K1B03              C305            
Q_CAP_0402-0.1UF,10V,10%,X7R,TA CH4102K1B03              C328            
Q_CAP_0402-0.1UF,10V,10%,X7R,TA CH4102K1B03              C331            
Q_CAP_0402-0.1UF,10V,10%,X7R,TA CH4102K1B03              C332            
Q_CAP_0402-0.1UF,10V,10%,X7R,TA CH4102K1B03              C333            
Q_CAP_0402-0.1UF,10V,10%,X7R,TA CH4102K1B03              C334            

----------------

Q_CAP_0402-0.1UF,25V,10%,EMPTYA CH4104K1B00              C22             

----------------

Q_CAP_0402-0.1UF,25V,10%,X7R,CA CH4104K1B00              C6              
Q_CAP_0402-0.1UF,25V,10%,X7R,CA CH4104K1B00              C7              
Q_CAP_0402-0.1UF,25V,10%,X7R,CA CH4104K1B00              C8              
Q_CAP_0402-0.1UF,25V,10%,X7R,CA CH4104K1B00              C10             
Q_CAP_0402-0.1UF,25V,10%,X7R,CA CH4104K1B00              C13             
Q_CAP_0402-0.1UF,25V,10%,X7R,CA CH4104K1B00              C14             
Q_CAP_0402-0.1UF,25V,10%,X7R,CA CH4104K1B00              C17             
Q_CAP_0402-0.1UF,25V,10%,X7R,CA CH4104K1B00              C18             
Q_CAP_0402-0.1UF,25V,10%,X7R,CA CH4104K1B00              C19             
Q_CAP_0402-0.1UF,25V,10%,X7R,CA CH4104K1B00              C20             
Q_CAP_0402-0.1UF,25V,10%,X7R,CA CH4104K1B00              C23             
Q_CAP_0402-0.1UF,25V,10%,X7R,CA CH4104K1B00              C24             
Q_CAP_0402-0.1UF,25V,10%,X7R,CA CH4104K1B00              C25             
Q_CAP_0402-0.1UF,25V,10%,X7R,CA CH4104K1B00              C26             
Q_CAP_0402-0.1UF,25V,10%,X7R,CA CH4104K1B00              C27             
Q_CAP_0402-0.1UF,25V,10%,X7R,CA CH4104K1B00              C28             
Q_CAP_0402-0.1UF,25V,10%,X7R,CA CH4104K1B00              C29             
Q_CAP_0402-0.1UF,25V,10%,X7R,CA CH4104K1B00              C31             
Q_CAP_0402-0.1UF,25V,10%,X7R,CA CH4104K1B00              C33             
Q_CAP_0402-0.1UF,25V,10%,X7R,CA CH4104K1B00              C34             
Q_CAP_0402-0.1UF,25V,10%,X7R,CA CH4104K1B00              C36             
Q_CAP_0402-0.1UF,25V,10%,X7R,CA CH4104K1B00              C37             
Q_CAP_0402-0.1UF,25V,10%,X7R,CA CH4104K1B00              C39             
Q_CAP_0402-0.1UF,25V,10%,X7R,CA CH4104K1B00              C41             
Q_CAP_0402-0.1UF,25V,10%,X7R,CA CH4104K1B00              C45             
Q_CAP_0402-0.1UF,25V,10%,X7R,CA CH4104K1B00              C49             
Q_CAP_0402-0.1UF,25V,10%,X7R,CA CH4104K1B00              C50             
Q_CAP_0402-0.1UF,25V,10%,X7R,CA CH4104K1B00              C51             
Q_CAP_0402-0.1UF,25V,10%,X7R,CA CH4104K1B00              C54             
Q_CAP_0402-0.1UF,25V,10%,X7R,CA CH4104K1B00              C57             
Q_CAP_0402-0.1UF,25V,10%,X7R,CA CH4104K1B00              C59             
Q_CAP_0402-0.1UF,25V,10%,X7R,CA CH4104K1B00              C65             
Q_CAP_0402-0.1UF,25V,10%,X7R,CA CH4104K1B00              C66             
Q_CAP_0402-0.1UF,25V,10%,X7R,CA CH4104K1B00              C68             
Q_CAP_0402-0.1UF,25V,10%,X7R,CA CH4104K1B00              C69             
Q_CAP_0402-0.1UF,25V,10%,X7R,CA CH4104K1B00              C70             
Q_CAP_0402-0.1UF,25V,10%,X7R,CA CH4104K1B00              C71             
Q_CAP_0402-0.1UF,25V,10%,X7R,CA CH4104K1B00              C72             
Q_CAP_0402-0.1UF,25V,10%,X7R,CA CH4104K1B00              C73             
Q_CAP_0402-0.1UF,25V,10%,X7R,CA CH4104K1B00              C74             
Q_CAP_0402-0.1UF,25V,10%,X7R,CA CH4104K1B00              C76             
Q_CAP_0402-0.1UF,25V,10%,X7R,CA CH4104K1B00              C77             
Q_CAP_0402-0.1UF,25V,10%,X7R,CA CH4104K1B00              C79             
Q_CAP_0402-0.1UF,25V,10%,X7R,CA CH4104K1B00              C81             
Q_CAP_0402-0.1UF,25V,10%,X7R,CA CH4104K1B00              C82             
Q_CAP_0402-0.1UF,25V,10%,X7R,CA CH4104K1B00              C83             
Q_CAP_0402-0.1UF,25V,10%,X7R,CA CH4104K1B00              C84             
Q_CAP_0402-0.1UF,25V,10%,X7R,CA CH4104K1B00              C85             
Q_CAP_0402-0.1UF,25V,10%,X7R,CA CH4104K1B00              C86             
Q_CAP_0402-0.1UF,25V,10%,X7R,CA CH4104K1B00              C87             
Q_CAP_0402-0.1UF,25V,10%,X7R,CA CH4104K1B00              C88             
Q_CAP_0402-0.1UF,25V,10%,X7R,CA CH4104K1B00              C89             
Q_CAP_0402-0.1UF,25V,10%,X7R,CA CH4104K1B00              C91             
Q_CAP_0402-0.1UF,25V,10%,X7R,CA CH4104K1B00              C92             
Q_CAP_0402-0.1UF,25V,10%,X7R,CA CH4104K1B00              C93             
Q_CAP_0402-0.1UF,25V,10%,X7R,CA CH4104K1B00              C94             
Q_CAP_0402-0.1UF,25V,10%,X7R,CA CH4104K1B00              C95             
Q_CAP_0402-0.1UF,25V,10%,X7R,CA CH4104K1B00              C96             
Q_CAP_0402-0.1UF,25V,10%,X7R,CA CH4104K1B00              C97             
Q_CAP_0402-0.1UF,25V,10%,X7R,CA CH4104K1B00              C98             
Q_CAP_0402-0.1UF,25V,10%,X7R,CA CH4104K1B00              C99             
Q_CAP_0402-0.1UF,25V,10%,X7R,CA CH4104K1B00              C100            
Q_CAP_0402-0.1UF,25V,10%,X7R,CA CH4104K1B00              C101            
Q_CAP_0402-0.1UF,25V,10%,X7R,CA CH4104K1B00              C102            
Q_CAP_0402-0.1UF,25V,10%,X7R,CA CH4104K1B00              C103            
Q_CAP_0402-0.1UF,25V,10%,X7R,CA CH4104K1B00              C105            
Q_CAP_0402-0.1UF,25V,10%,X7R,CA CH4104K1B00              C107            
Q_CAP_0402-0.1UF,25V,10%,X7R,CA CH4104K1B00              C109            
Q_CAP_0402-0.1UF,25V,10%,X7R,CA CH4104K1B00              C112            
Q_CAP_0402-0.1UF,25V,10%,X7R,CA CH4104K1B00              C130            
Q_CAP_0402-0.1UF,25V,10%,X7R,CA CH4104K1B00              C139            
Q_CAP_0402-0.1UF,25V,10%,X7R,CA CH4104K1B00              C140            
Q_CAP_0402-0.1UF,25V,10%,X7R,CA CH4104K1B00              C144            
Q_CAP_0402-0.1UF,25V,10%,X7R,CA CH4104K1B00              C146            
Q_CAP_0402-0.1UF,25V,10%,X7R,CA CH4104K1B00              C147            
Q_CAP_0402-0.1UF,25V,10%,X7R,CA CH4104K1B00              C148            
Q_CAP_0402-0.1UF,25V,10%,X7R,CA CH4104K1B00              C149            
Q_CAP_0402-0.1UF,25V,10%,X7R,CA CH4104K1B00              C157            
Q_CAP_0402-0.1UF,25V,10%,X7R,CA CH4104K1B00              C158            
Q_CAP_0402-0.1UF,25V,10%,X7R,CA CH4104K1B00              C159            
Q_CAP_0402-0.1UF,25V,10%,X7R,CA CH4104K1B00              C160            
Q_CAP_0402-0.1UF,25V,10%,X7R,CA CH4104K1B00              C168            
Q_CAP_0402-0.1UF,25V,10%,X7R,CA CH4104K1B00              C174            
Q_CAP_0402-0.1UF,25V,10%,X7R,CA CH4104K1B00              C175            
Q_CAP_0402-0.1UF,25V,10%,X7R,CA CH4104K1B00              C185            
Q_CAP_0402-0.1UF,25V,10%,X7R,CA CH4104K1B00              C186            
Q_CAP_0402-0.1UF,25V,10%,X7R,CA CH4104K1B00              C187            
Q_CAP_0402-0.1UF,25V,10%,X7R,CA CH4104K1B00              C189            
Q_CAP_0402-0.1UF,25V,10%,X7R,CA CH4104K1B00              C191            
Q_CAP_0402-0.1UF,25V,10%,X7R,CA CH4104K1B00              C192            
Q_CAP_0402-0.1UF,25V,10%,X7R,CA CH4104K1B00              C194            
Q_CAP_0402-0.1UF,25V,10%,X7R,CA CH4104K1B00              C195            
Q_CAP_0402-0.1UF,25V,10%,X7R,CA CH4104K1B00              C196            
Q_CAP_0402-0.1UF,25V,10%,X7R,CA CH4104K1B00              C197            
Q_CAP_0402-0.1UF,25V,10%,X7R,CA CH4104K1B00              C200            
Q_CAP_0402-0.1UF,25V,10%,X7R,CA CH4104K1B00              C201            
Q_CAP_0402-0.1UF,25V,10%,X7R,CA CH4104K1B00              C202            
Q_CAP_0402-0.1UF,25V,10%,X7R,CA CH4104K1B00              C203            
Q_CAP_0402-0.1UF,25V,10%,X7R,CA CH4104K1B00              C217            
Q_CAP_0402-0.1UF,25V,10%,X7R,CA CH4104K1B00              C220            
Q_CAP_0402-0.1UF,25V,10%,X7R,CA CH4104K1B00              C221            
Q_CAP_0402-0.1UF,25V,10%,X7R,CA CH4104K1B00              C222            
Q_CAP_0402-0.1UF,25V,10%,X7R,CA CH4104K1B00              C225            
Q_CAP_0402-0.1UF,25V,10%,X7R,CA CH4104K1B00              C249            
Q_CAP_0402-0.1UF,25V,10%,X7R,CA CH4104K1B00              C253            
Q_CAP_0402-0.1UF,25V,10%,X7R,CA CH4104K1B00              C255            
Q_CAP_0402-0.1UF,25V,10%,X7R,CA CH4104K1B00              C263            
Q_CAP_0402-0.1UF,25V,10%,X7R,CA CH4104K1B00              C264            
Q_CAP_0402-0.1UF,25V,10%,X7R,CA CH4104K1B00              C266            
Q_CAP_0402-0.1UF,25V,10%,X7R,CA CH4104K1B00              C269            
Q_CAP_0402-0.1UF,25V,10%,X7R,CA CH4104K1B00              C274            
Q_CAP_0402-0.1UF,25V,10%,X7R,CA CH4104K1B00              C278            
Q_CAP_0402-0.1UF,25V,10%,X7R,CA CH4104K1B00              C279            
Q_CAP_0402-0.1UF,25V,10%,X7R,CA CH4104K1B00              C281            
Q_CAP_0402-0.1UF,25V,10%,X7R,CA CH4104K1B00              C284            
Q_CAP_0402-0.1UF,25V,10%,X7R,CA CH4104K1B00              C287            
Q_CAP_0402-0.1UF,25V,10%,X7R,CA CH4104K1B00              C289            
Q_CAP_0402-0.1UF,25V,10%,X7R,CA CH4104K1B00              C290            
Q_CAP_0402-0.1UF,25V,10%,X7R,CA CH4104K1B00              C295            
Q_CAP_0402-0.1UF,25V,10%,X7R,CA CH4104K1B00              C298            
Q_CAP_0402-0.1UF,25V,10%,X7R,CA CH4104K1B00              C299            
Q_CAP_0402-0.1UF,25V,10%,X7R,CA CH4104K1B00              C302            
Q_CAP_0402-0.1UF,25V,10%,X7R,CA CH4104K1B00              C303            
Q_CAP_0402-0.1UF,25V,10%,X7R,CA CH4104K1B00              C306            
Q_CAP_0402-0.1UF,25V,10%,X7R,CA CH4104K1B00              C307            
Q_CAP_0402-0.1UF,25V,10%,X7R,CA CH4104K1B00              C308            
Q_CAP_0402-0.1UF,25V,10%,X7R,CA CH4104K1B00              C309            
Q_CAP_0402-0.1UF,25V,10%,X7R,CA CH4104K1B00              C310            
Q_CAP_0402-0.1UF,25V,10%,X7R,CA CH4104K1B00              C311            
Q_CAP_0402-0.1UF,25V,10%,X7R,CA CH4104K1B00              C312            
Q_CAP_0402-0.1UF,25V,10%,X7R,CA CH4104K1B00              C313            
Q_CAP_0402-0.1UF,25V,10%,X7R,CA CH4104K1B00              C314            
Q_CAP_0402-0.1UF,25V,10%,X7R,CA CH4104K1B00              C315            
Q_CAP_0402-0.1UF,25V,10%,X7R,CA CH4104K1B00              C317            
Q_CAP_0402-0.1UF,25V,10%,X7R,CA CH4104K1B00              C318            
Q_CAP_0402-0.1UF,25V,10%,X7R,CA CH4104K1B00              C319            
Q_CAP_0402-0.1UF,25V,10%,X7R,CA CH4104K1B00              C320            
Q_CAP_0402-0.1UF,25V,10%,X7R,CA CH4104K1B00              C321            
Q_CAP_0402-0.1UF,25V,10%,X7R,CA CH4104K1B00              C323            
Q_CAP_0402-0.1UF,25V,10%,X7R,CA CH4104K1B00              C339            
Q_CAP_0402-0.1UF,25V,10%,X7R,CA CH4104K1B00              C340            
Q_CAP_0402-0.1UF,25V,10%,X7R,CA CH4104K1B00              C341            
Q_CAP_0402-0.1UF,25V,10%,X7R,CA CH4104K1B00              C342            
Q_CAP_0402-0.1UF,25V,10%,X7R,CA CH4104K1B00              C343            
Q_CAP_0402-0.1UF,25V,10%,X7R,CA CH4104K1B00              C344            
Q_CAP_0402-0.1UF,25V,10%,X7R,CA CH4104K1B00              C345            
Q_CAP_0402-0.1UF,25V,10%,X7R,CA CH4104K1B00              PC205           
Q_CAP_0402-0.1UF,25V,10%,X7R,CA CH4104K1B00              PC210           
Q_CAP_0402-0.1UF,25V,10%,X7R,CA CH4104K1B00              PC212           
Q_CAP_0402-0.1UF,25V,10%,X7R,CA CH4104K1B00              PC223           
Q_CAP_0402-0.1UF,25V,10%,X7R,CA CH4104K1B00              PC225           
Q_CAP_0402-0.1UF,25V,10%,X7R,CA CH4104K1B00              PC235           
Q_CAP_0402-0.1UF,25V,10%,X7R,CA CH4104K1B00              PC249           
Q_CAP_0402-0.1UF,25V,10%,X7R,CA CH4104K1B00              PC253           
Q_CAP_0402-0.1UF,25V,10%,X7R,CA CH4104K1B00              PC255           
Q_CAP_0402-0.1UF,25V,10%,X7R,CA CH4104K1B00              PC263           
Q_CAP_0402-0.1UF,25V,10%,X7R,CA CH4104K1B00              PC266           
Q_CAP_0402-0.1UF,25V,10%,X7R,CA CH4104K1B00              PC271           

----------------

Q_CAP_0402-0.22UF,16V,10%,EMPTA CH4223K1B00              C229            

----------------

Q_CAP_0402-0.22UF,16V,10%,X7R,A CH4223K1B00              C12             
Q_CAP_0402-0.22UF,16V,10%,X7R,A CH4223K1B00              PC216           
Q_CAP_0402-0.22UF,16V,10%,X7R,A CH4223K1B00              PC224           
Q_CAP_0402-0.22UF,16V,10%,X7R,A CH4223K1B00              PC254           
Q_CAP_0402-0.22UF,16V,10%,X7R,A CH4223K1B00              PC264           

----------------

Q_CAP_0402-100PF,50V,5%,EMPTY,A CH11006JB18              C213            
Q_CAP_0402-100PF,50V,5%,EMPTY,A CH11006JB18              C214            

----------------

Q_CAP_0402-100PF,50V,5%,NPO,CHA CH11006JB00              C9              
Q_CAP_0402-100PF,50V,5%,NPO,CHA CH11006JB00              C165            
Q_CAP_0402-100PF,50V,5%,NPO,CHA CH11006JB00              C166            
Q_CAP_0402-100PF,50V,5%,NPO,CHA CH11006JB00              C167            
Q_CAP_0402-100PF,50V,5%,NPO,CHA CH11006JB00              C275            
Q_CAP_0402-100PF,50V,5%,NPO,CHA CH11006JB00              PC239           

----------------

Q_CAP_0402-10PF,50V,1%,NPO,TMPA CH0106F0B00              C205            
Q_CAP_0402-10PF,50V,1%,NPO,TMPA CH0106F0B00              C206            
Q_CAP_0402-10PF,50V,1%,NPO,TMPA CH0106F0B00              C207            

----------------

Q_CAP_0402-10PF,50V,5%,COG,CH0A CH01006JB08              C211            
Q_CAP_0402-10PF,50V,5%,COG,CH0A CH01006JB08              C212            

----------------

Q_CAP_0402-1UF,16V,10%,EMPTY,TA CH5103K9B00              C181            
Q_CAP_0402-1UF,16V,10%,EMPTY,TA CH5103K9B00              C267            
Q_CAP_0402-1UF,16V,10%,EMPTY,TA CH5103K9B00              C268            
Q_CAP_0402-1UF,16V,10%,EMPTY,TA CH5103K9B00              C270            
Q_CAP_0402-1UF,16V,10%,EMPTY,TA CH5103K9B00              C273            

----------------

Q_CAP_0402-2.2UF,10V,20%,X5R,TA CH5222M9B07              C193            
Q_CAP_0402-2.2UF,10V,20%,X5R,TA CH5222M9B07              C272            

----------------

Q_CAP_0402-2200PF,50V,10%,X7R,A CH22206KB16              C63             

----------------

Q_CAP_0402-22PF,50V,5%,EMPTY,TA CH02206JB08              C152            

----------------

Q_CAP_0402-3300PF,50V,10%,X7R,A CH2336K1B12              PC273           

----------------

Q_CAP_0402-4.7UF,10V,10%,X5R,CA CH5472K9B00              C347            
Q_CAP_0402-4.7UF,10V,10%,X5R,CA CH5472K9B00              C348            
Q_CAP_0402-4.7UF,10V,10%,X5R,CA CH5472K9B00              C350            

----------------

Q_CAP_0402-470PF,50V,10%,X7R,TA CH14706KB18              C172            
Q_CAP_0402-470PF,50V,10%,X7R,TA CH14706KB18              C178            
Q_CAP_0402-470PF,50V,10%,X7R,TA CH14706KB18              C179            
Q_CAP_0402-470PF,50V,10%,X7R,TA CH14706KB18              C324            
Q_CAP_0402-470PF,50V,10%,X7R,TA CH14706KB18              C326            

----------------

Q_CAP_0603-1UF,16V,10%,EMPTY,TA CH5103K1900              C204            

----------------

Q_CAP_0805-22UF,4V,20%,X6S,TMPA CH622KMEA01              PC256           
Q_CAP_0805-22UF,4V,20%,X6S,TMPA CH622KMEA01              PC257           
Q_CAP_0805-22UF,4V,20%,X6S,TMPA CH622KMEA01              PC258           
Q_CAP_0805-22UF,4V,20%,X6S,TMPA CH622KMEA01              PC259           
Q_CAP_0805-22UF,4V,20%,X6S,TMPA CH622KMEA01              PC267           
Q_CAP_0805-22UF,4V,20%,X6S,TMPA CH622KMEA01              PC268           
Q_CAP_0805-22UF,4V,20%,X6S,TMPA CH622KMEA01              PC269           
Q_CAP_0805-22UF,4V,20%,X6S,TMPA CH622KMEA01              PC270           

----------------

Q_CAP_1206-47UF ,10V,20%,X5R,CA CH6472M9200              C177            
Q_CAP_1206-47UF ,10V,20%,X5R,CA CH6472M9200              C327            

----------------

Q_CAP_C0402-0.001UF,50V,10%,X7A CH30106KB19              C150            
Q_CAP_C0402-0.001UF,50V,10%,X7A CH30106KB19              C151            
Q_CAP_C0402-0.001UF,50V,10%,X7A CH30106KB19              C153            
Q_CAP_C0402-0.001UF,50V,10%,X7A CH30106KB19              C154            
Q_CAP_C0402-0.001UF,50V,10%,X7A CH30106KB19              C155            
Q_CAP_C0402-0.001UF,50V,10%,X7A CH30106KB19              C156            

----------------

Q_CAP_C0402-0.01UF,50V,10%,EMPA CH31006KB18              C21             
Q_CAP_C0402-0.01UF,50V,10%,EMPA CH31006KB18              C142            
Q_CAP_C0402-0.01UF,50V,10%,EMPA CH31006KB18              C169            

----------------

Q_CAP_C0402-0.01UF,50V,10%,X7RA CH31006KB18              C133            
Q_CAP_C0402-0.01UF,50V,10%,X7RA CH31006KB18              C134            
Q_CAP_C0402-0.01UF,50V,10%,X7RA CH31006KB18              C135            
Q_CAP_C0402-0.01UF,50V,10%,X7RA CH31006KB18              C136            
Q_CAP_C0402-0.01UF,50V,10%,X7RA CH31006KB18              C137            
Q_CAP_C0402-0.01UF,50V,10%,X7RA CH31006KB18              C138            
Q_CAP_C0402-0.01UF,50V,10%,X7RA CH31006KB18              C163            
Q_CAP_C0402-0.01UF,50V,10%,X7RA CH31006KB18              C164            
Q_CAP_C0402-0.01UF,50V,10%,X7RA CH31006KB18              C170            
Q_CAP_C0402-0.01UF,50V,10%,X7RA CH31006KB18              C246            
Q_CAP_C0402-0.01UF,50V,10%,X7RA CH31006KB18              C258            
Q_CAP_C0402-0.01UF,50V,10%,X7RA CH31006KB18              C259            

----------------

Q_CAP_C0402-0.1UF,16V,10%,EMPTA CH4103K1B08              C252            

----------------

Q_CAP_C0402-0.1UF,16V,10%,X7R,A CH4103K1B08              C180            
Q_CAP_C0402-0.1UF,16V,10%,X7R,A CH4103K1B08              C182            
Q_CAP_C0402-0.1UF,16V,10%,X7R,A CH4103K1B08              C240            
Q_CAP_C0402-0.1UF,16V,10%,X7R,A CH4103K1B08              C251            

----------------

Q_CAP_C0402-0.1UF,25V,10%,X6S,A CH4104KEB00              C173            

----------------

Q_CAP_C0402-10UF,10V,20%,X5R,CA CH6102M9B00              C143            
Q_CAP_C0402-10UF,10V,20%,X5R,CA CH6102M9B00              C215            
Q_CAP_C0402-10UF,10V,20%,X5R,CA CH6102M9B00              C224            
Q_CAP_C0402-10UF,10V,20%,X5R,CA CH6102M9B00              C248            

----------------

Q_CAP_C0402-10UF,6.3V,20%,X6S,A CH6101MEB01              C15             
Q_CAP_C0402-10UF,6.3V,20%,X6S,A CH6101MEB01              C16             
Q_CAP_C0402-10UF,6.3V,20%,X6S,A CH6101MEB01              C262            

----------------

Q_CAP_C0402-12PF,50V,5%,C0G,CHA CH01206JB05              C141            
Q_CAP_C0402-12PF,50V,5%,C0G,CHA CH01206JB05              C145            

----------------

Q_CAP_C0402-1UF,25V,10%,EMPTY,A CH5104KEB02              C230            

----------------

Q_CAP_C0402-1UF,25V,10%,X6S,CHA CH5104KEB02              C2              
Q_CAP_C0402-1UF,25V,10%,X6S,CHA CH5104KEB02              C3              
Q_CAP_C0402-1UF,25V,10%,X6S,CHA CH5104KEB02              C4              
Q_CAP_C0402-1UF,25V,10%,X6S,CHA CH5104KEB02              C5              
Q_CAP_C0402-1UF,25V,10%,X6S,CHA CH5104KEB02              C30             
Q_CAP_C0402-1UF,25V,10%,X6S,CHA CH5104KEB02              C32             
Q_CAP_C0402-1UF,25V,10%,X6S,CHA CH5104KEB02              C35             
Q_CAP_C0402-1UF,25V,10%,X6S,CHA CH5104KEB02              C38             
Q_CAP_C0402-1UF,25V,10%,X6S,CHA CH5104KEB02              C43             
Q_CAP_C0402-1UF,25V,10%,X6S,CHA CH5104KEB02              C46             
Q_CAP_C0402-1UF,25V,10%,X6S,CHA CH5104KEB02              C47             
Q_CAP_C0402-1UF,25V,10%,X6S,CHA CH5104KEB02              C48             
Q_CAP_C0402-1UF,25V,10%,X6S,CHA CH5104KEB02              C52             
Q_CAP_C0402-1UF,25V,10%,X6S,CHA CH5104KEB02              C53             
Q_CAP_C0402-1UF,25V,10%,X6S,CHA CH5104KEB02              C56             
Q_CAP_C0402-1UF,25V,10%,X6S,CHA CH5104KEB02              C58             
Q_CAP_C0402-1UF,25V,10%,X6S,CHA CH5104KEB02              C60             
Q_CAP_C0402-1UF,25V,10%,X6S,CHA CH5104KEB02              C61             
Q_CAP_C0402-1UF,25V,10%,X6S,CHA CH5104KEB02              C62             
Q_CAP_C0402-1UF,25V,10%,X6S,CHA CH5104KEB02              C64             
Q_CAP_C0402-1UF,25V,10%,X6S,CHA CH5104KEB02              C67             
Q_CAP_C0402-1UF,25V,10%,X6S,CHA CH5104KEB02              C75             
Q_CAP_C0402-1UF,25V,10%,X6S,CHA CH5104KEB02              C78             
Q_CAP_C0402-1UF,25V,10%,X6S,CHA CH5104KEB02              C80             
Q_CAP_C0402-1UF,25V,10%,X6S,CHA CH5104KEB02              C90             
Q_CAP_C0402-1UF,25V,10%,X6S,CHA CH5104KEB02              C104            
Q_CAP_C0402-1UF,25V,10%,X6S,CHA CH5104KEB02              C106            
Q_CAP_C0402-1UF,25V,10%,X6S,CHA CH5104KEB02              C108            
Q_CAP_C0402-1UF,25V,10%,X6S,CHA CH5104KEB02              C110            
Q_CAP_C0402-1UF,25V,10%,X6S,CHA CH5104KEB02              C111            
Q_CAP_C0402-1UF,25V,10%,X6S,CHA CH5104KEB02              C114            
Q_CAP_C0402-1UF,25V,10%,X6S,CHA CH5104KEB02              C115            
Q_CAP_C0402-1UF,25V,10%,X6S,CHA CH5104KEB02              C116            
Q_CAP_C0402-1UF,25V,10%,X6S,CHA CH5104KEB02              C117            
Q_CAP_C0402-1UF,25V,10%,X6S,CHA CH5104KEB02              C119            
Q_CAP_C0402-1UF,25V,10%,X6S,CHA CH5104KEB02              C122            
Q_CAP_C0402-1UF,25V,10%,X6S,CHA CH5104KEB02              C127            
Q_CAP_C0402-1UF,25V,10%,X6S,CHA CH5104KEB02              C128            
Q_CAP_C0402-1UF,25V,10%,X6S,CHA CH5104KEB02              C129            
Q_CAP_C0402-1UF,25V,10%,X6S,CHA CH5104KEB02              C161            
Q_CAP_C0402-1UF,25V,10%,X6S,CHA CH5104KEB02              C198            
Q_CAP_C0402-1UF,25V,10%,X6S,CHA CH5104KEB02              C199            
Q_CAP_C0402-1UF,25V,10%,X6S,CHA CH5104KEB02              C244            
Q_CAP_C0402-1UF,25V,10%,X6S,CHA CH5104KEB02              C256            
Q_CAP_C0402-1UF,25V,10%,X6S,CHA CH5104KEB02              C257            
Q_CAP_C0402-1UF,25V,10%,X6S,CHA CH5104KEB02              C277            
Q_CAP_C0402-1UF,25V,10%,X6S,CHA CH5104KEB02              C282            
Q_CAP_C0402-1UF,25V,10%,X6S,CHA CH5104KEB02              PC208           
Q_CAP_C0402-1UF,25V,10%,X6S,CHA CH5104KEB02              PC221           
Q_CAP_C0402-1UF,25V,10%,X6S,CHA CH5104KEB02              PC233           
Q_CAP_C0402-1UF,25V,10%,X6S,CHA CH5104KEB02              PC243           
Q_CAP_C0402-1UF,25V,10%,X6S,CHA CH5104KEB02              PC250           
Q_CAP_C0402-1UF,25V,10%,X6S,CHA CH5104KEB02              PC260           

----------------

Q_CAP_C0402-1UF,6.3V,10%,EMPTYA CH5101KEB00              C231            

----------------

Q_CAP_C0402-22UF,6.3V,20%,X5R,A CH6221M9B01              C346            
Q_CAP_C0402-22UF,6.3V,20%,X5R,A CH6221M9B01              C349            

----------------

Q_CAP_C0402-33PF,50V,1%,C0G,CHA CH0336F0B00              C208            
Q_CAP_C0402-33PF,50V,1%,C0G,CHA CH0336F0B00              C209            
Q_CAP_C0402-33PF,50V,1%,C0G,CHA CH0336F0B00              C210            

----------------

Q_CAP_C0402-4.7UF,10V,10%,X5R,A CH5472K9B02              C40             
Q_CAP_C0402-4.7UF,10V,10%,X5R,A CH5472K9B02              C44             

----------------

Q_CAP_C0402-4700P,25V,10%,EMPTA CH2474K1B08              C223            

----------------

Q_CAP_C0402-68PF,50V,5%,COG,CHA CH06806JB01              PC272           

----------------

Q_CAP_C0603-10UF,16V,20%,X6S,CA CH6103ME902              C162            
Q_CAP_C0603-10UF,16V,20%,X6S,CA CH6103ME902              C188            
Q_CAP_C0603-10UF,16V,20%,X6S,CA CH6103ME902              C190            

----------------

Q_CAP_C0603-22UF,10V,20%,EMPTYA CH6222M9901              C234            

----------------

Q_CAP_C0603-22UF,10V,20%,X5R,CA CH6222M9901              C113            
Q_CAP_C0603-22UF,10V,20%,X5R,CA CH6222M9901              C120            
Q_CAP_C0603-22UF,10V,20%,X5R,CA CH6222M9901              C125            
Q_CAP_C0603-22UF,10V,20%,X5R,CA CH6222M9901              C131            
Q_CAP_C0603-22UF,10V,20%,X5R,CA CH6222M9901              C132            
Q_CAP_C0603-22UF,10V,20%,X5R,CA CH6222M9901              C183            
Q_CAP_C0603-22UF,10V,20%,X5R,CA CH6222M9901              C184            

----------------

Q_CAP_C0603-22UF,6.3V,20%,EMPTA CH6221ME900              C232            

----------------

Q_CAP_C0603-22UF,6.3V,20%,X6S,A CH6221ME900              C42             
Q_CAP_C0603-22UF,6.3V,20%,X6S,A CH6221ME900              C55             
Q_CAP_C0603-22UF,6.3V,20%,X6S,A CH6221ME900              C118            
Q_CAP_C0603-22UF,6.3V,20%,X6S,A CH6221ME900              C121            
Q_CAP_C0603-22UF,6.3V,20%,X6S,A CH6221ME900              C123            
Q_CAP_C0603-22UF,6.3V,20%,X6S,A CH6221ME900              C124            
Q_CAP_C0603-22UF,6.3V,20%,X6S,A CH6221ME900              C126            

----------------

Q_CAP_C0603-4.7UF,25V,10%,X6S,A CH5474KE906              C1              

----------------

Q_CAP_C0805-10UF,25V,10%,X6S,CA CH6104KEA00              PC206           
Q_CAP_C0805-10UF,25V,10%,X6S,CA CH6104KEA00              PC207           
Q_CAP_C0805-10UF,25V,10%,X6S,CA CH6104KEA00              PC218           
Q_CAP_C0805-10UF,25V,10%,X6S,CA CH6104KEA00              PC219           
Q_CAP_C0805-10UF,25V,10%,X6S,CA CH6104KEA00              PC237           
Q_CAP_C0805-10UF,25V,10%,X6S,CA CH6104KEA00              PC242           
Q_CAP_C0805-10UF,25V,10%,X6S,CA CH6104KEA00              PC248           
Q_CAP_C0805-10UF,25V,10%,X6S,CA CH6104KEA00              PC251           
Q_CAP_C0805-10UF,25V,10%,X6S,CA CH6104KEA00              PC252           
Q_CAP_C0805-10UF,25V,10%,X6S,CA CH6104KEA00              PC261           
Q_CAP_C0805-10UF,25V,10%,X6S,CA CH6104KEA00              PC262           
Q_CAP_C0805-10UF,25V,10%,X6S,CA CH6104KEA00              PC307           

----------------

Q_CAP_C0805-22UF,10V,20%,X6S,CA CH6222MEA00              PC226           
Q_CAP_C0805-22UF,10V,20%,X6S,CA CH6222MEA00              PC227           
Q_CAP_C0805-22UF,10V,20%,X6S,CA CH6222MEA00              PC228           
Q_CAP_C0805-22UF,10V,20%,X6S,CA CH6222MEA00              PC229           

----------------

Q_CAP_C0805-22UF,16V,20%,X6S,CA CH6223MEA00              C171            
Q_CAP_C0805-22UF,16V,20%,X6S,CA CH6223MEA00              PC213           
Q_CAP_C0805-22UF,16V,20%,X6S,CA CH6223MEA00              PC214           
Q_CAP_C0805-22UF,16V,20%,X6S,CA CH6223MEA00              PC215           
Q_CAP_C0805-22UF,16V,20%,X6S,CA CH6223MEA00              PC217           

----------------

Q_CAP_C0805-22UF,25V,20%,X5R,CA CH6224M9A00              C329            
Q_CAP_C0805-22UF,25V,20%,X5R,CA CH6224M9A00              C330            

----------------

Q_DIODE_SMLF-SDMK0340L-7-F,IC,A BC000340033              D17             

----------------

Q_FUSE_SMLF-0.5A/6V,IC,DK050TPA DK050TPU011              L1              

----------------

Q_FUSE_SMLF-1.1A/8V,IC,DK110TPA DK110TPU003              FS1             

----------------

Q_INDUCTOR4P_12-67/320MA,320MAA CX21SN67000              L24             

----------------

Q_INDUCTOR4P_12-67/320MA,320MAB CX21SN67000              L23             

----------------

Q_INDUCTOR_SMLF-1UH,IND,CV-10BA CV-10B0MZ13              PL31            
Q_INDUCTOR_SMLF-1UH,IND,CV-10BA CV-10B0MZ13              PL33            

----------------

Q_INDUCTOR_SMLF-220/1500MA,INDA CX221T15000              L20             

----------------

Q_INDUCTOR_SMLF-3.3UH/6A,IND,CA CV-3360MZ07              PL35            

----------------

Q_INDUCTOR_SMLF-4.7UH,IND,CV-4A CV-47A0MZ10              PL34            

----------------

Q_INDUCTOR_SMLF-47/300MA,IND,CA CX8BA470003              L28             
Q_INDUCTOR_SMLF-47/300MA,IND,CA CX8BA470003              L29             
Q_INDUCTOR_SMLF-47/300MA,IND,CA CX8BA470003              L30             

----------------

Q_INDUCTOR_SMLF-BLM15PX121SN1DA CX5PX121001              L18             
Q_INDUCTOR_SMLF-BLM15PX121SN1DA CX5PX121001              L31             
Q_INDUCTOR_SMLF-BLM15PX121SN1DA CX5PX121001              L32             
Q_INDUCTOR_SMLF-BLM15PX121SN1DA CX5PX121001              L33             
Q_INDUCTOR_SMLF-BLM15PX121SN1DA CX5PX121001              L34             

----------------

Q_INDUCTOR_SMLF-BLM18EG121SN1DA CX8EG121000              L17             
Q_INDUCTOR_SMLF-BLM18EG121SN1DA CX8EG121000              L26             
Q_INDUCTOR_SMLF-BLM18EG121SN1DA CX8EG121000              L27             

----------------

Q_INDUCTOR_SMLF-BLM18PG121SN1DA CX8PG121009              L3              
Q_INDUCTOR_SMLF-BLM18PG121SN1DA CX8PG121009              L4              
Q_INDUCTOR_SMLF-BLM18PG121SN1DA CX8PG121009              L5              
Q_INDUCTOR_SMLF-BLM18PG121SN1DA CX8PG121009              L6              
Q_INDUCTOR_SMLF-BLM18PG121SN1DA CX8PG121009              L7              
Q_INDUCTOR_SMLF-BLM18PG121SN1DA CX8PG121009              L8              
Q_INDUCTOR_SMLF-BLM18PG121SN1DA CX8PG121009              L9              
Q_INDUCTOR_SMLF-BLM18PG121SN1DA CX8PG121009              L10             
Q_INDUCTOR_SMLF-BLM18PG121SN1DA CX8PG121009              L11             
Q_INDUCTOR_SMLF-BLM18PG121SN1DA CX8PG121009              L12             
Q_INDUCTOR_SMLF-BLM18PG121SN1DA CX8PG121009              L13             
Q_INDUCTOR_SMLF-BLM18PG121SN1DA CX8PG121009              L14             
Q_INDUCTOR_SMLF-BLM18PG121SN1DA CX8PG121009              L15             
Q_INDUCTOR_SMLF-BLM18PG121SN1DA CX8PG121009              L16             

----------------

Q_INDUCTOR_SMLF-BLM18PG121SN1DB CX8PG121009              L2              

----------------

Q_INDUCTOR_SMLF-BLM18SN220TN1DA CX220TN1001              PL4             
Q_INDUCTOR_SMLF-BLM18SN220TN1DA CX220TN1001              PL19            
Q_INDUCTOR_SMLF-BLM18SN220TN1DA CX220TN1001              PL29            
Q_INDUCTOR_SMLF-BLM18SN220TN1DA CX220TN1001              PL32            

----------------

Q_LED_SMLF-LED_BLUE,12-215/BHCA BEBL0261Z00              D14             
Q_LED_SMLF-LED_BLUE,12-215/BHCA BEBL0261Z00              D15             

----------------

Q_LED_SMLF-LED_GREEN,19-213/GVA BEGR0278Z00              D0              
Q_LED_SMLF-LED_GREEN,19-213/GVA BEGR0278Z00              D1              
Q_LED_SMLF-LED_GREEN,19-213/GVA BEGR0278Z00              D2              
Q_LED_SMLF-LED_GREEN,19-213/GVA BEGR0278Z00              D3              
Q_LED_SMLF-LED_GREEN,19-213/GVA BEGR0278Z00              D8              

----------------

Q_LED_SMLF-LED_RED,19-217/R6C-A BERD0034Z07              D4              
Q_LED_SMLF-LED_RED,19-217/R6C-A BERD0034Z07              D5              
Q_LED_SMLF-LED_RED,19-217/R6C-A BERD0034Z07              D6              
Q_LED_SMLF-LED_RED,19-217/R6C-A BERD0034Z07              D7              

----------------

Q_RES_0201LF-1.5K,1%,1/20W,CHIA CS21501FE01              R401            

----------------

Q_RES_0201LF-27.4,1%,1/20W,CHIA CS02741FE07              R402            
Q_RES_0201LF-27.4,1%,1/20W,CHIA CS02741FE07              R403            

----------------

Q_RES_0201LF-47K,1%,1/20W,CHIPA CS34701FE00              R776            

----------------

Q_RES_0402LF -49.9K,1%,1/16W ,A CS34992FB10              R233            
Q_RES_0402LF -49.9K,1%,1/16W ,A CS34992FB10              R234            

----------------

Q_RES_0402LF-0,5%,1/16W,CHIP,CA CS00002JB38              PR193           
Q_RES_0402LF-0,5%,1/16W,CHIP,CA CS00002JB38              PR274           
Q_RES_0402LF-0,5%,1/16W,CHIP,CA CS00002JB38              R2              
Q_RES_0402LF-0,5%,1/16W,CHIP,CA CS00002JB38              R3              
Q_RES_0402LF-0,5%,1/16W,CHIP,CA CS00002JB38              R18             
Q_RES_0402LF-0,5%,1/16W,CHIP,CA CS00002JB38              R19             
Q_RES_0402LF-0,5%,1/16W,CHIP,CA CS00002JB38              R20             
Q_RES_0402LF-0,5%,1/16W,CHIP,CA CS00002JB38              R21             
Q_RES_0402LF-0,5%,1/16W,CHIP,CA CS00002JB38              R24             
Q_RES_0402LF-0,5%,1/16W,CHIP,CA CS00002JB38              R26             
Q_RES_0402LF-0,5%,1/16W,CHIP,CA CS00002JB38              R30             
Q_RES_0402LF-0,5%,1/16W,CHIP,CA CS00002JB38              R35             
Q_RES_0402LF-0,5%,1/16W,CHIP,CA CS00002JB38              R39             
Q_RES_0402LF-0,5%,1/16W,CHIP,CA CS00002JB38              R49             
Q_RES_0402LF-0,5%,1/16W,CHIP,CA CS00002JB38              R51             
Q_RES_0402LF-0,5%,1/16W,CHIP,CA CS00002JB38              R83             
Q_RES_0402LF-0,5%,1/16W,CHIP,CA CS00002JB38              R86             
Q_RES_0402LF-0,5%,1/16W,CHIP,CA CS00002JB38              R97             
Q_RES_0402LF-0,5%,1/16W,CHIP,CA CS00002JB38              R98             
Q_RES_0402LF-0,5%,1/16W,CHIP,CA CS00002JB38              R99             
Q_RES_0402LF-0,5%,1/16W,CHIP,CA CS00002JB38              R100            
Q_RES_0402LF-0,5%,1/16W,CHIP,CA CS00002JB38              R106            
Q_RES_0402LF-0,5%,1/16W,CHIP,CA CS00002JB38              R109            
Q_RES_0402LF-0,5%,1/16W,CHIP,CA CS00002JB38              R110            
Q_RES_0402LF-0,5%,1/16W,CHIP,CA CS00002JB38              R113            
Q_RES_0402LF-0,5%,1/16W,CHIP,CA CS00002JB38              R135            
Q_RES_0402LF-0,5%,1/16W,CHIP,CA CS00002JB38              R141            
Q_RES_0402LF-0,5%,1/16W,CHIP,CA CS00002JB38              R155            
Q_RES_0402LF-0,5%,1/16W,CHIP,CA CS00002JB38              R207            
Q_RES_0402LF-0,5%,1/16W,CHIP,CA CS00002JB38              R213            
Q_RES_0402LF-0,5%,1/16W,CHIP,CA CS00002JB38              R216            
Q_RES_0402LF-0,5%,1/16W,CHIP,CA CS00002JB38              R217            
Q_RES_0402LF-0,5%,1/16W,CHIP,CA CS00002JB38              R218            
Q_RES_0402LF-0,5%,1/16W,CHIP,CA CS00002JB38              R220            
Q_RES_0402LF-0,5%,1/16W,CHIP,CA CS00002JB38              R231            
Q_RES_0402LF-0,5%,1/16W,CHIP,CA CS00002JB38              R271            
Q_RES_0402LF-0,5%,1/16W,CHIP,CA CS00002JB38              R272            
Q_RES_0402LF-0,5%,1/16W,CHIP,CA CS00002JB38              R275            
Q_RES_0402LF-0,5%,1/16W,CHIP,CA CS00002JB38              R276            
Q_RES_0402LF-0,5%,1/16W,CHIP,CA CS00002JB38              R277            
Q_RES_0402LF-0,5%,1/16W,CHIP,CA CS00002JB38              R279            
Q_RES_0402LF-0,5%,1/16W,CHIP,CA CS00002JB38              R281            
Q_RES_0402LF-0,5%,1/16W,CHIP,CA CS00002JB38              R282            
Q_RES_0402LF-0,5%,1/16W,CHIP,CA CS00002JB38              R292            
Q_RES_0402LF-0,5%,1/16W,CHIP,CA CS00002JB38              R293            
Q_RES_0402LF-0,5%,1/16W,CHIP,CA CS00002JB38              R294            
Q_RES_0402LF-0,5%,1/16W,CHIP,CA CS00002JB38              R297            
Q_RES_0402LF-0,5%,1/16W,CHIP,CA CS00002JB38              R300            
Q_RES_0402LF-0,5%,1/16W,CHIP,CA CS00002JB38              R302            
Q_RES_0402LF-0,5%,1/16W,CHIP,CA CS00002JB38              R303            
Q_RES_0402LF-0,5%,1/16W,CHIP,CA CS00002JB38              R315            
Q_RES_0402LF-0,5%,1/16W,CHIP,CA CS00002JB38              R316            
Q_RES_0402LF-0,5%,1/16W,CHIP,CA CS00002JB38              R317            
Q_RES_0402LF-0,5%,1/16W,CHIP,CA CS00002JB38              R318            
Q_RES_0402LF-0,5%,1/16W,CHIP,CA CS00002JB38              R319            
Q_RES_0402LF-0,5%,1/16W,CHIP,CA CS00002JB38              R320            
Q_RES_0402LF-0,5%,1/16W,CHIP,CA CS00002JB38              R321            
Q_RES_0402LF-0,5%,1/16W,CHIP,CA CS00002JB38              R322            
Q_RES_0402LF-0,5%,1/16W,CHIP,CA CS00002JB38              R323            
Q_RES_0402LF-0,5%,1/16W,CHIP,CA CS00002JB38              R379            
Q_RES_0402LF-0,5%,1/16W,CHIP,CA CS00002JB38              R380            
Q_RES_0402LF-0,5%,1/16W,CHIP,CA CS00002JB38              R381            
Q_RES_0402LF-0,5%,1/16W,CHIP,CA CS00002JB38              R382            
Q_RES_0402LF-0,5%,1/16W,CHIP,CA CS00002JB38              R384            
Q_RES_0402LF-0,5%,1/16W,CHIP,CA CS00002JB38              R385            
Q_RES_0402LF-0,5%,1/16W,CHIP,CA CS00002JB38              R386            
Q_RES_0402LF-0,5%,1/16W,CHIP,CA CS00002JB38              R393            
Q_RES_0402LF-0,5%,1/16W,CHIP,CA CS00002JB38              R397            
Q_RES_0402LF-0,5%,1/16W,CHIP,CA CS00002JB38              R399            
Q_RES_0402LF-0,5%,1/16W,CHIP,CA CS00002JB38              R406            
Q_RES_0402LF-0,5%,1/16W,CHIP,CA CS00002JB38              R447            
Q_RES_0402LF-0,5%,1/16W,CHIP,CA CS00002JB38              R451            
Q_RES_0402LF-0,5%,1/16W,CHIP,CA CS00002JB38              R453            
Q_RES_0402LF-0,5%,1/16W,CHIP,CA CS00002JB38              R454            
Q_RES_0402LF-0,5%,1/16W,CHIP,CA CS00002JB38              R456            
Q_RES_0402LF-0,5%,1/16W,CHIP,CA CS00002JB38              R457            
Q_RES_0402LF-0,5%,1/16W,CHIP,CA CS00002JB38              R495            
Q_RES_0402LF-0,5%,1/16W,CHIP,CA CS00002JB38              R498            
Q_RES_0402LF-0,5%,1/16W,CHIP,CA CS00002JB38              R499            
Q_RES_0402LF-0,5%,1/16W,CHIP,CA CS00002JB38              R500            
Q_RES_0402LF-0,5%,1/16W,CHIP,CA CS00002JB38              R501            
Q_RES_0402LF-0,5%,1/16W,CHIP,CA CS00002JB38              R503            
Q_RES_0402LF-0,5%,1/16W,CHIP,CA CS00002JB38              R505            
Q_RES_0402LF-0,5%,1/16W,CHIP,CA CS00002JB38              R519            
Q_RES_0402LF-0,5%,1/16W,CHIP,CA CS00002JB38              R520            
Q_RES_0402LF-0,5%,1/16W,CHIP,CA CS00002JB38              R527            
Q_RES_0402LF-0,5%,1/16W,CHIP,CA CS00002JB38              R528            
Q_RES_0402LF-0,5%,1/16W,CHIP,CA CS00002JB38              R542            
Q_RES_0402LF-0,5%,1/16W,CHIP,CA CS00002JB38              R564            
Q_RES_0402LF-0,5%,1/16W,CHIP,CA CS00002JB38              R565            
Q_RES_0402LF-0,5%,1/16W,CHIP,CA CS00002JB38              R566            
Q_RES_0402LF-0,5%,1/16W,CHIP,CA CS00002JB38              R571            
Q_RES_0402LF-0,5%,1/16W,CHIP,CA CS00002JB38              R572            
Q_RES_0402LF-0,5%,1/16W,CHIP,CA CS00002JB38              R573            
Q_RES_0402LF-0,5%,1/16W,CHIP,CA CS00002JB38              R574            
Q_RES_0402LF-0,5%,1/16W,CHIP,CA CS00002JB38              R575            
Q_RES_0402LF-0,5%,1/16W,CHIP,CA CS00002JB38              R576            
Q_RES_0402LF-0,5%,1/16W,CHIP,CA CS00002JB38              R577            
Q_RES_0402LF-0,5%,1/16W,CHIP,CA CS00002JB38              R578            
Q_RES_0402LF-0,5%,1/16W,CHIP,CA CS00002JB38              R579            
Q_RES_0402LF-0,5%,1/16W,CHIP,CA CS00002JB38              R634            
Q_RES_0402LF-0,5%,1/16W,CHIP,CA CS00002JB38              R636            
Q_RES_0402LF-0,5%,1/16W,CHIP,CA CS00002JB38              R637            
Q_RES_0402LF-0,5%,1/16W,CHIP,CA CS00002JB38              R708            
Q_RES_0402LF-0,5%,1/16W,CHIP,CA CS00002JB38              R728            
Q_RES_0402LF-0,5%,1/16W,CHIP,CA CS00002JB38              R779            
Q_RES_0402LF-0,5%,1/16W,CHIP,CA CS00002JB38              R783            
Q_RES_0402LF-0,5%,1/16W,CHIP,CA CS00002JB38              R822            

----------------

Q_RES_0402LF-0,5%,1/16W,EMPTY,A CS00002JB38              PR205           
Q_RES_0402LF-0,5%,1/16W,EMPTY,A CS00002JB38              PR275           
Q_RES_0402LF-0,5%,1/16W,EMPTY,A CS00002JB38              R1              
Q_RES_0402LF-0,5%,1/16W,EMPTY,A CS00002JB38              R43             
Q_RES_0402LF-0,5%,1/16W,EMPTY,A CS00002JB38              R63             
Q_RES_0402LF-0,5%,1/16W,EMPTY,A CS00002JB38              R64             
Q_RES_0402LF-0,5%,1/16W,EMPTY,A CS00002JB38              R95             
Q_RES_0402LF-0,5%,1/16W,EMPTY,A CS00002JB38              R154            
Q_RES_0402LF-0,5%,1/16W,EMPTY,A CS00002JB38              R156            
Q_RES_0402LF-0,5%,1/16W,EMPTY,A CS00002JB38              R208            
Q_RES_0402LF-0,5%,1/16W,EMPTY,A CS00002JB38              R214            
Q_RES_0402LF-0,5%,1/16W,EMPTY,A CS00002JB38              R232            
Q_RES_0402LF-0,5%,1/16W,EMPTY,A CS00002JB38              R278            
Q_RES_0402LF-0,5%,1/16W,EMPTY,A CS00002JB38              R280            
Q_RES_0402LF-0,5%,1/16W,EMPTY,A CS00002JB38              R301            
Q_RES_0402LF-0,5%,1/16W,EMPTY,A CS00002JB38              R432            
Q_RES_0402LF-0,5%,1/16W,EMPTY,A CS00002JB38              R450            
Q_RES_0402LF-0,5%,1/16W,EMPTY,A CS00002JB38              R529            
Q_RES_0402LF-0,5%,1/16W,EMPTY,A CS00002JB38              R530            
Q_RES_0402LF-0,5%,1/16W,EMPTY,A CS00002JB38              R585            
Q_RES_0402LF-0,5%,1/16W,EMPTY,A CS00002JB38              R616            
Q_RES_0402LF-0,5%,1/16W,EMPTY,A CS00002JB38              R711            
Q_RES_0402LF-0,5%,1/16W,EMPTY,A CS00002JB38              R764            
Q_RES_0402LF-0,5%,1/16W,EMPTY,A CS00002JB38              R780            
Q_RES_0402LF-0,5%,1/16W,EMPTY,A CS00002JB38              R781            
Q_RES_0402LF-0,5%,1/16W,EMPTY,A CS00002JB38              R782            
Q_RES_0402LF-0,5%,1/16W,EMPTY,A CS00002JB38              R784            

----------------

Q_RES_0402LF-1.24K,1%,1/16W,CHA CS21242FB20              R400            

----------------

Q_RES_0402LF-1.5K,1%,1/16W,CHIA CS21502FB14              R285            

----------------

Q_RES_0402LF-1.5K,1%,1/16W,EMPA CS21502FB14              R283            

----------------

Q_RES_0402LF-1.69K,1%,1/16W,CHA CS21692FB01              R791            

----------------

Q_RES_0402LF-10,1%,1/16W,CHIP,A CS01002FB21              R816            

----------------

Q_RES_0402LF-100,1%,1/16W,CHIPA CS11002FB22              R94             
Q_RES_0402LF-100,1%,1/16W,CHIPA CS11002FB22              R134            
Q_RES_0402LF-100,1%,1/16W,CHIPA CS11002FB22              R412            
Q_RES_0402LF-100,1%,1/16W,CHIPA CS11002FB22              R413            
Q_RES_0402LF-100,1%,1/16W,CHIPA CS11002FB22              R415            
Q_RES_0402LF-100,1%,1/16W,CHIPA CS11002FB22              R419            
Q_RES_0402LF-100,1%,1/16W,CHIPA CS11002FB22              R431            
Q_RES_0402LF-100,1%,1/16W,CHIPA CS11002FB22              R506            
Q_RES_0402LF-100,1%,1/16W,CHIPA CS11002FB22              R507            

----------------

Q_RES_0402LF-100,1%,1/16W,EMPTA CS11002FB22              R125            
Q_RES_0402LF-100,1%,1/16W,EMPTA CS11002FB22              R411            
Q_RES_0402LF-100,1%,1/16W,EMPTA CS11002FB22              R417            

----------------

Q_RES_0402LF-100K,0.1%,1/16W,CA CS41002BB06              PR543           

----------------

Q_RES_0402LF-100K,1%,1/16W,CHIA CS41002FB28              PR245           
Q_RES_0402LF-100K,1%,1/16W,CHIA CS41002FB28              PR522           
Q_RES_0402LF-100K,1%,1/16W,CHIA CS41002FB28              R66             
Q_RES_0402LF-100K,1%,1/16W,CHIA CS41002FB28              R193            
Q_RES_0402LF-100K,1%,1/16W,CHIA CS41002FB28              R391            
Q_RES_0402LF-100K,1%,1/16W,CHIA CS41002FB28              R392            
Q_RES_0402LF-100K,1%,1/16W,CHIA CS41002FB28              R614            
Q_RES_0402LF-100K,1%,1/16W,CHIA CS41002FB28              R620            
Q_RES_0402LF-100K,1%,1/16W,CHIA CS41002FB28              R710            
Q_RES_0402LF-100K,1%,1/16W,CHIA CS41002FB28              R778            
Q_RES_0402LF-100K,1%,1/16W,CHIA CS41002FB28              R823            

----------------

Q_RES_0402LF-100K,1%,1/16W,CHIB CS41002FB09              R314            

----------------

Q_RES_0402LF-100K,1%,1/16W,EMPA CS41002FB09              R118            

----------------

Q_RES_0402LF-100K,1%,1/16W,EMPB CS41002FB28              R219            
Q_RES_0402LF-100K,1%,1/16W,EMPB CS41002FB28              R274            
Q_RES_0402LF-100K,1%,1/16W,EMPB CS41002FB28              R296            
Q_RES_0402LF-100K,1%,1/16W,EMPB CS41002FB28              R817            
Q_RES_0402LF-100K,1%,1/16W,EMPB CS41002FB28              R818            
Q_RES_0402LF-100K,1%,1/16W,EMPB CS41002FB28              R819            
Q_RES_0402LF-100K,1%,1/16W,EMPB CS41002FB28              R820            

----------------

Q_RES_0402LF-10K,0.10%,1/16W,CA CS31002BB00              R202            
Q_RES_0402LF-10K,0.10%,1/16W,CA CS31002BB00              R203            
Q_RES_0402LF-10K,0.10%,1/16W,CA CS31002BB00              R204            
Q_RES_0402LF-10K,0.10%,1/16W,CA CS31002BB00              R226            
Q_RES_0402LF-10K,0.10%,1/16W,CA CS31002BB00              R227            
Q_RES_0402LF-10K,0.10%,1/16W,CA CS31002BB00              R228            
Q_RES_0402LF-10K,0.10%,1/16W,CA CS31002BB00              R230            
Q_RES_0402LF-10K,0.10%,1/16W,CA CS31002BB00              R523            
Q_RES_0402LF-10K,0.10%,1/16W,CA CS31002BB00              R808            
Q_RES_0402LF-10K,0.10%,1/16W,CA CS31002BB00              R809            
Q_RES_0402LF-10K,0.10%,1/16W,CA CS31002BB00              R810            
Q_RES_0402LF-10K,0.10%,1/16W,CA CS31002BB00              R811            
Q_RES_0402LF-10K,0.10%,1/16W,CA CS31002BB00              R814            
Q_RES_0402LF-10K,0.10%,1/16W,CA CS31002BB00              R815            

----------------

Q_RES_0402LF-10K,1%,1/16W,CHIPA CS31002FB26              PR242           
Q_RES_0402LF-10K,1%,1/16W,CHIPA CS31002FB26              PR244           
Q_RES_0402LF-10K,1%,1/16W,CHIPA CS31002FB26              PR255           
Q_RES_0402LF-10K,1%,1/16W,CHIPA CS31002FB26              PR498           
Q_RES_0402LF-10K,1%,1/16W,CHIPA CS31002FB26              PR500           
Q_RES_0402LF-10K,1%,1/16W,CHIPA CS31002FB26              R10             
Q_RES_0402LF-10K,1%,1/16W,CHIPA CS31002FB26              R41             
Q_RES_0402LF-10K,1%,1/16W,CHIPA CS31002FB26              R42             
Q_RES_0402LF-10K,1%,1/16W,CHIPA CS31002FB26              R50             
Q_RES_0402LF-10K,1%,1/16W,CHIPA CS31002FB26              R59             
Q_RES_0402LF-10K,1%,1/16W,CHIPA CS31002FB26              R209            
Q_RES_0402LF-10K,1%,1/16W,CHIPA CS31002FB26              R210            
Q_RES_0402LF-10K,1%,1/16W,CHIPA CS31002FB26              R211            
Q_RES_0402LF-10K,1%,1/16W,CHIPA CS31002FB26              R289            
Q_RES_0402LF-10K,1%,1/16W,CHIPA CS31002FB26              R383            
Q_RES_0402LF-10K,1%,1/16W,CHIPA CS31002FB26              R398            
Q_RES_0402LF-10K,1%,1/16W,CHIPA CS31002FB26              R464            
Q_RES_0402LF-10K,1%,1/16W,CHIPA CS31002FB26              R497            
Q_RES_0402LF-10K,1%,1/16W,CHIPA CS31002FB26              R508            
Q_RES_0402LF-10K,1%,1/16W,CHIPA CS31002FB26              R618            
Q_RES_0402LF-10K,1%,1/16W,CHIPA CS31002FB26              R709            
Q_RES_0402LF-10K,1%,1/16W,CHIPA CS31002FB26              R715            
Q_RES_0402LF-10K,1%,1/16W,CHIPA CS31002FB26              R716            
Q_RES_0402LF-10K,1%,1/16W,CHIPA CS31002FB26              R866            

----------------

Q_RES_0402LF-10K,1%,1/16W,EMPTA CS31002FB26              R105            
Q_RES_0402LF-10K,1%,1/16W,EMPTA CS31002FB26              R164            
Q_RES_0402LF-10K,1%,1/16W,EMPTA CS31002FB26              R295            
Q_RES_0402LF-10K,1%,1/16W,EMPTA CS31002FB26              R655            
Q_RES_0402LF-10K,1%,1/16W,EMPTA CS31002FB26              R656            
Q_RES_0402LF-10K,1%,1/16W,EMPTA CS31002FB26              R657            
Q_RES_0402LF-10K,1%,1/16W,EMPTA CS31002FB26              R658            
Q_RES_0402LF-10K,1%,1/16W,EMPTA CS31002FB26              R659            
Q_RES_0402LF-10K,1%,1/16W,EMPTA CS31002FB26              R660            
Q_RES_0402LF-10K,1%,1/16W,EMPTA CS31002FB26              R661            
Q_RES_0402LF-10K,1%,1/16W,EMPTA CS31002FB26              R662            
Q_RES_0402LF-10K,1%,1/16W,EMPTA CS31002FB26              R663            

----------------

Q_RES_0402LF-10K,1%,1/16W,EMPTB CS31002FB13              R377            

----------------

Q_RES_0402LF-12.4K,1%,1/16W,CHA CS31242FB13              PR526           
Q_RES_0402LF-12.4K,1%,1/16W,CHA CS31242FB13              PR530           

----------------

Q_RES_0402LF-120,1%,1/16W,CHIPA CS11202FB11              R326            
Q_RES_0402LF-120,1%,1/16W,CHIPA CS11202FB11              R327            
Q_RES_0402LF-120,1%,1/16W,CHIPA CS11202FB11              R328            
Q_RES_0402LF-120,1%,1/16W,CHIPA CS11202FB11              R329            
Q_RES_0402LF-120,1%,1/16W,CHIPA CS11202FB11              R330            
Q_RES_0402LF-120,1%,1/16W,CHIPA CS11202FB11              R331            
Q_RES_0402LF-120,1%,1/16W,CHIPA CS11202FB11              R332            
Q_RES_0402LF-120,1%,1/16W,CHIPA CS11202FB11              R333            
Q_RES_0402LF-120,1%,1/16W,CHIPA CS11202FB11              R334            
Q_RES_0402LF-120,1%,1/16W,CHIPA CS11202FB11              R335            
Q_RES_0402LF-120,1%,1/16W,CHIPA CS11202FB11              R336            
Q_RES_0402LF-120,1%,1/16W,CHIPA CS11202FB11              R337            
Q_RES_0402LF-120,1%,1/16W,CHIPA CS11202FB11              R338            
Q_RES_0402LF-120,1%,1/16W,CHIPA CS11202FB11              R339            
Q_RES_0402LF-120,1%,1/16W,CHIPA CS11202FB11              R340            
Q_RES_0402LF-120,1%,1/16W,CHIPA CS11202FB11              R341            
Q_RES_0402LF-120,1%,1/16W,CHIPA CS11202FB11              R342            
Q_RES_0402LF-120,1%,1/16W,CHIPA CS11202FB11              R343            
Q_RES_0402LF-120,1%,1/16W,CHIPA CS11202FB11              R344            
Q_RES_0402LF-120,1%,1/16W,CHIPA CS11202FB11              R345            
Q_RES_0402LF-120,1%,1/16W,CHIPA CS11202FB11              R346            
Q_RES_0402LF-120,1%,1/16W,CHIPA CS11202FB11              R347            
Q_RES_0402LF-120,1%,1/16W,CHIPA CS11202FB11              R348            
Q_RES_0402LF-120,1%,1/16W,CHIPA CS11202FB11              R349            
Q_RES_0402LF-120,1%,1/16W,CHIPA CS11202FB11              R351            
Q_RES_0402LF-120,1%,1/16W,CHIPA CS11202FB11              R352            
Q_RES_0402LF-120,1%,1/16W,CHIPA CS11202FB11              R353            
Q_RES_0402LF-120,1%,1/16W,CHIPA CS11202FB11              R354            
Q_RES_0402LF-120,1%,1/16W,CHIPA CS11202FB11              R355            
Q_RES_0402LF-120,1%,1/16W,CHIPA CS11202FB11              R356            
Q_RES_0402LF-120,1%,1/16W,CHIPA CS11202FB11              R357            
Q_RES_0402LF-120,1%,1/16W,CHIPA CS11202FB11              R358            
Q_RES_0402LF-120,1%,1/16W,CHIPA CS11202FB11              R359            
Q_RES_0402LF-120,1%,1/16W,CHIPA CS11202FB11              R360            
Q_RES_0402LF-120,1%,1/16W,CHIPA CS11202FB11              R361            
Q_RES_0402LF-120,1%,1/16W,CHIPA CS11202FB11              R362            
Q_RES_0402LF-120,1%,1/16W,CHIPA CS11202FB11              R363            
Q_RES_0402LF-120,1%,1/16W,CHIPA CS11202FB11              R364            
Q_RES_0402LF-120,1%,1/16W,CHIPA CS11202FB11              R365            
Q_RES_0402LF-120,1%,1/16W,CHIPA CS11202FB11              R366            
Q_RES_0402LF-120,1%,1/16W,CHIPA CS11202FB11              R367            
Q_RES_0402LF-120,1%,1/16W,CHIPA CS11202FB11              R368            
Q_RES_0402LF-120,1%,1/16W,CHIPA CS11202FB11              R369            
Q_RES_0402LF-120,1%,1/16W,CHIPA CS11202FB11              R370            
Q_RES_0402LF-120,1%,1/16W,CHIPA CS11202FB11              R371            
Q_RES_0402LF-120,1%,1/16W,CHIPA CS11202FB11              R372            
Q_RES_0402LF-120,1%,1/16W,CHIPA CS11202FB11              R373            
Q_RES_0402LF-120,1%,1/16W,CHIPA CS11202FB11              R374            

----------------

Q_RES_0402LF-120,1%,1/16W,EMPTA CS11202FB11              R350            
Q_RES_0402LF-120,1%,1/16W,EMPTA CS11202FB11              R375            

----------------

Q_RES_0402LF-12K,1%,1/16W,CHIPA CS31202FB15              R830            
Q_RES_0402LF-12K,1%,1/16W,CHIPA CS31202FB15              R832            

----------------

Q_RES_0402LF-13.3K,1%,1/16W,CHA CS21332FB02              PR525           

----------------

Q_RES_0402LF-15.8K,1%,1/16W,CHA CS31582FB12              R785            

----------------

Q_RES_0402LF-150,1%,1/16W,CHIPA CS11502FB21              R22             
Q_RES_0402LF-150,1%,1/16W,CHIPA CS11502FB21              R23             
Q_RES_0402LF-150,1%,1/16W,CHIPA CS11502FB21              R25             
Q_RES_0402LF-150,1%,1/16W,CHIPA CS11502FB21              R87             
Q_RES_0402LF-150,1%,1/16W,CHIPA CS11502FB21              R88             
Q_RES_0402LF-150,1%,1/16W,CHIPA CS11502FB21              R89             

----------------

Q_RES_0402LF-150K,1%,1/16W,CHIA CS41502FB18              PR496           

----------------

Q_RES_0402LF-15K,1%,1/16W,CHIPA CS31502FB24              R831            

----------------

Q_RES_0402LF-1K,1%,1/16W,CHIP,A CS21002FB24              R4              
Q_RES_0402LF-1K,1%,1/16W,CHIP,A CS21002FB24              R5              
Q_RES_0402LF-1K,1%,1/16W,CHIP,A CS21002FB24              R15             
Q_RES_0402LF-1K,1%,1/16W,CHIP,A CS21002FB24              R324            
Q_RES_0402LF-1K,1%,1/16W,CHIP,A CS21002FB24              R325            
Q_RES_0402LF-1K,1%,1/16W,CHIP,A CS21002FB24              R568            
Q_RES_0402LF-1K,1%,1/16W,CHIP,A CS21002FB24              R569            
Q_RES_0402LF-1K,1%,1/16W,CHIP,A CS21002FB24              R775            
Q_RES_0402LF-1K,1%,1/16W,CHIP,A CS21002FB24              R795            
Q_RES_0402LF-1K,1%,1/16W,CHIP,A CS21002FB24              R796            

----------------

Q_RES_0402LF-1K,1%,1/16W,EMPTYA CS21002FB24              R73             
Q_RES_0402LF-1K,1%,1/16W,EMPTYA CS21002FB24              R77             
Q_RES_0402LF-1K,1%,1/16W,EMPTYA CS21002FB24              R633            
Q_RES_0402LF-1K,1%,1/16W,EMPTYA CS21002FB24              R684            
Q_RES_0402LF-1K,1%,1/16W,EMPTYA CS21002FB24              R685            

----------------

Q_RES_0402LF-1M,1%,1/16W,CHIP,A CS51002FB11              R395            
Q_RES_0402LF-1M,1%,1/16W,CHIP,A CS51002FB11              R396            

----------------

Q_RES_0402LF-2.21K    ,1%  ,1/A CS22212FB11              R16             
Q_RES_0402LF-2.21K    ,1%  ,1/A CS22212FB11              R17             

----------------

Q_RES_0402LF-2.2K ,5%,1/16W,CHA CS22202JB18              R91             
Q_RES_0402LF-2.2K ,5%,1/16W,CHA CS22202JB18              R92             

----------------

Q_RES_0402LF-2.74K,1%,1/16W,CHA CS22742FB00              R235            

----------------

Q_RES_0402LF-2.87K,1%,1/16W,CHA CS22872FB10              R789            
Q_RES_0402LF-2.87K,1%,1/16W,CHA CS22872FB10              R797            

----------------

Q_RES_0402LF-200K,1%,1/16W,CHIA CS42002FB12              R777            

----------------

Q_RES_0402LF-20K,1%,1/16W,CHIPA CS32002FB29              R205            
Q_RES_0402LF-20K,1%,1/16W,CHIPA CS32002FB29              R378            

----------------

Q_RES_0402LF-22,1%,1/16W,CHIP,A CS02202FB02              R286            
Q_RES_0402LF-22,1%,1/16W,CHIP,A CS02202FB02              R288            

----------------

Q_RES_0402LF-22,5%,1/16W,CHIP,A CS02202JB22              R538            
Q_RES_0402LF-22,5%,1/16W,CHIP,A CS02202JB22              R539            
Q_RES_0402LF-22,5%,1/16W,CHIP,A CS02202JB22              R628            
Q_RES_0402LF-22,5%,1/16W,CHIP,A CS02202JB22              R629            
Q_RES_0402LF-22,5%,1/16W,CHIP,A CS02202JB22              R630            
Q_RES_0402LF-22,5%,1/16W,CHIP,A CS02202JB22              R631            

----------------

Q_RES_0402LF-220,5%,1/16W,CHIPA CS12202JB24              R304            
Q_RES_0402LF-220,5%,1/16W,CHIPA CS12202JB24              R305            
Q_RES_0402LF-220,5%,1/16W,CHIPA CS12202JB24              R306            

----------------

Q_RES_0402LF-240,1%,1/16W,CHIPA CS12402FB03              R6              
Q_RES_0402LF-240,1%,1/16W,CHIPA CS12402FB03              R127            

----------------

Q_RES_0402LF-25.5K,1%,1/16W,CHA CS32552FB11              R829            

----------------

Q_RES_0402LF-2K,1%,1/16W,CHIP,A CS22002FB19              R74             
Q_RES_0402LF-2K,1%,1/16W,CHIP,A CS22002FB19              R75             
Q_RES_0402LF-2K,1%,1/16W,CHIP,A CS22002FB19              R76             
Q_RES_0402LF-2K,1%,1/16W,CHIP,A CS22002FB19              R78             
Q_RES_0402LF-2K,1%,1/16W,CHIP,A CS22002FB19              R79             
Q_RES_0402LF-2K,1%,1/16W,CHIP,A CS22002FB19              R82             
Q_RES_0402LF-2K,1%,1/16W,CHIP,A CS22002FB19              R124            
Q_RES_0402LF-2K,1%,1/16W,CHIP,A CS22002FB19              R467            
Q_RES_0402LF-2K,1%,1/16W,CHIP,A CS22002FB19              R714            
Q_RES_0402LF-2K,1%,1/16W,CHIP,A CS22002FB19              R786            
Q_RES_0402LF-2K,1%,1/16W,CHIP,A CS22002FB19              R788            
Q_RES_0402LF-2K,1%,1/16W,CHIP,A CS22002FB19              R790            
Q_RES_0402LF-2K,1%,1/16W,CHIP,A CS22002FB19              R792            
Q_RES_0402LF-2K,1%,1/16W,CHIP,A CS22002FB19              R794            
Q_RES_0402LF-2K,1%,1/16W,CHIP,A CS22002FB19              R798            

----------------

Q_RES_0402LF-2K,1%,1/16W,EMPTYA CS22002FB19              R40             

----------------

Q_RES_0402LF-33       ,1%  ,1/A CS03302FB19              R28             
Q_RES_0402LF-33       ,1%  ,1/A CS03302FB19              R29             
Q_RES_0402LF-33       ,1%  ,1/A CS03302FB19              R36             
Q_RES_0402LF-33       ,1%  ,1/A CS03302FB19              R37             
Q_RES_0402LF-33       ,1%  ,1/A CS03302FB19              R46             
Q_RES_0402LF-33       ,1%  ,1/A CS03302FB19              R52             
Q_RES_0402LF-33       ,1%  ,1/A CS03302FB19              R53             
Q_RES_0402LF-33       ,1%  ,1/A CS03302FB19              R54             
Q_RES_0402LF-33       ,1%  ,1/A CS03302FB19              R60             
Q_RES_0402LF-33       ,1%  ,1/A CS03302FB19              R65             
Q_RES_0402LF-33       ,1%  ,1/A CS03302FB19              R71             
Q_RES_0402LF-33       ,1%  ,1/A CS03302FB19              R84             
Q_RES_0402LF-33       ,1%  ,1/A CS03302FB19              R85             
Q_RES_0402LF-33       ,1%  ,1/A CS03302FB19              R90             
Q_RES_0402LF-33       ,1%  ,1/A CS03302FB19              R93             
Q_RES_0402LF-33       ,1%  ,1/A CS03302FB19              R96             
Q_RES_0402LF-33       ,1%  ,1/A CS03302FB19              R102            
Q_RES_0402LF-33       ,1%  ,1/A CS03302FB19              R104            
Q_RES_0402LF-33       ,1%  ,1/A CS03302FB19              R111            
Q_RES_0402LF-33       ,1%  ,1/A CS03302FB19              R112            
Q_RES_0402LF-33       ,1%  ,1/A CS03302FB19              R114            
Q_RES_0402LF-33       ,1%  ,1/A CS03302FB19              R119            
Q_RES_0402LF-33       ,1%  ,1/A CS03302FB19              R120            
Q_RES_0402LF-33       ,1%  ,1/A CS03302FB19              R121            
Q_RES_0402LF-33       ,1%  ,1/A CS03302FB19              R122            
Q_RES_0402LF-33       ,1%  ,1/A CS03302FB19              R123            
Q_RES_0402LF-33       ,1%  ,1/A CS03302FB19              R128            
Q_RES_0402LF-33       ,1%  ,1/A CS03302FB19              R129            
Q_RES_0402LF-33       ,1%  ,1/A CS03302FB19              R130            
Q_RES_0402LF-33       ,1%  ,1/A CS03302FB19              R131            
Q_RES_0402LF-33       ,1%  ,1/A CS03302FB19              R132            
Q_RES_0402LF-33       ,1%  ,1/A CS03302FB19              R133            
Q_RES_0402LF-33       ,1%  ,1/A CS03302FB19              R137            
Q_RES_0402LF-33       ,1%  ,1/A CS03302FB19              R138            
Q_RES_0402LF-33       ,1%  ,1/A CS03302FB19              R139            
Q_RES_0402LF-33       ,1%  ,1/A CS03302FB19              R142            
Q_RES_0402LF-33       ,1%  ,1/A CS03302FB19              R143            
Q_RES_0402LF-33       ,1%  ,1/A CS03302FB19              R144            
Q_RES_0402LF-33       ,1%  ,1/A CS03302FB19              R146            
Q_RES_0402LF-33       ,1%  ,1/A CS03302FB19              R147            
Q_RES_0402LF-33       ,1%  ,1/A CS03302FB19              R148            
Q_RES_0402LF-33       ,1%  ,1/A CS03302FB19              R150            
Q_RES_0402LF-33       ,1%  ,1/A CS03302FB19              R151            
Q_RES_0402LF-33       ,1%  ,1/A CS03302FB19              R152            
Q_RES_0402LF-33       ,1%  ,1/A CS03302FB19              R153            
Q_RES_0402LF-33       ,1%  ,1/A CS03302FB19              R157            
Q_RES_0402LF-33       ,1%  ,1/A CS03302FB19              R158            
Q_RES_0402LF-33       ,1%  ,1/A CS03302FB19              R159            
Q_RES_0402LF-33       ,1%  ,1/A CS03302FB19              R160            
Q_RES_0402LF-33       ,1%  ,1/A CS03302FB19              R162            
Q_RES_0402LF-33       ,1%  ,1/A CS03302FB19              R165            
Q_RES_0402LF-33       ,1%  ,1/A CS03302FB19              R166            
Q_RES_0402LF-33       ,1%  ,1/A CS03302FB19              R168            
Q_RES_0402LF-33       ,1%  ,1/A CS03302FB19              R170            
Q_RES_0402LF-33       ,1%  ,1/A CS03302FB19              R171            
Q_RES_0402LF-33       ,1%  ,1/A CS03302FB19              R172            
Q_RES_0402LF-33       ,1%  ,1/A CS03302FB19              R173            
Q_RES_0402LF-33       ,1%  ,1/A CS03302FB19              R174            
Q_RES_0402LF-33       ,1%  ,1/A CS03302FB19              R175            
Q_RES_0402LF-33       ,1%  ,1/A CS03302FB19              R176            
Q_RES_0402LF-33       ,1%  ,1/A CS03302FB19              R177            
Q_RES_0402LF-33       ,1%  ,1/A CS03302FB19              R178            
Q_RES_0402LF-33       ,1%  ,1/A CS03302FB19              R179            
Q_RES_0402LF-33       ,1%  ,1/A CS03302FB19              R180            
Q_RES_0402LF-33       ,1%  ,1/A CS03302FB19              R181            
Q_RES_0402LF-33       ,1%  ,1/A CS03302FB19              R182            
Q_RES_0402LF-33       ,1%  ,1/A CS03302FB19              R183            
Q_RES_0402LF-33       ,1%  ,1/A CS03302FB19              R184            
Q_RES_0402LF-33       ,1%  ,1/A CS03302FB19              R185            
Q_RES_0402LF-33       ,1%  ,1/A CS03302FB19              R186            
Q_RES_0402LF-33       ,1%  ,1/A CS03302FB19              R187            
Q_RES_0402LF-33       ,1%  ,1/A CS03302FB19              R198            
Q_RES_0402LF-33       ,1%  ,1/A CS03302FB19              R199            
Q_RES_0402LF-33       ,1%  ,1/A CS03302FB19              R200            
Q_RES_0402LF-33       ,1%  ,1/A CS03302FB19              R201            
Q_RES_0402LF-33       ,1%  ,1/A CS03302FB19              R215            
Q_RES_0402LF-33       ,1%  ,1/A CS03302FB19              R221            
Q_RES_0402LF-33       ,1%  ,1/A CS03302FB19              R222            
Q_RES_0402LF-33       ,1%  ,1/A CS03302FB19              R223            
Q_RES_0402LF-33       ,1%  ,1/A CS03302FB19              R224            
Q_RES_0402LF-33       ,1%  ,1/A CS03302FB19              R225            
Q_RES_0402LF-33       ,1%  ,1/A CS03302FB19              R236            
Q_RES_0402LF-33       ,1%  ,1/A CS03302FB19              R237            
Q_RES_0402LF-33       ,1%  ,1/A CS03302FB19              R242            
Q_RES_0402LF-33       ,1%  ,1/A CS03302FB19              R243            
Q_RES_0402LF-33       ,1%  ,1/A CS03302FB19              R263            
Q_RES_0402LF-33       ,1%  ,1/A CS03302FB19              R270            
Q_RES_0402LF-33       ,1%  ,1/A CS03302FB19              R394            
Q_RES_0402LF-33       ,1%  ,1/A CS03302FB19              R404            
Q_RES_0402LF-33       ,1%  ,1/A CS03302FB19              R405            
Q_RES_0402LF-33       ,1%  ,1/A CS03302FB19              R408            
Q_RES_0402LF-33       ,1%  ,1/A CS03302FB19              R409            
Q_RES_0402LF-33       ,1%  ,1/A CS03302FB19              R410            
Q_RES_0402LF-33       ,1%  ,1/A CS03302FB19              R420            
Q_RES_0402LF-33       ,1%  ,1/A CS03302FB19              R421            
Q_RES_0402LF-33       ,1%  ,1/A CS03302FB19              R423            
Q_RES_0402LF-33       ,1%  ,1/A CS03302FB19              R424            
Q_RES_0402LF-33       ,1%  ,1/A CS03302FB19              R425            
Q_RES_0402LF-33       ,1%  ,1/A CS03302FB19              R426            
Q_RES_0402LF-33       ,1%  ,1/A CS03302FB19              R427            
Q_RES_0402LF-33       ,1%  ,1/A CS03302FB19              R433            
Q_RES_0402LF-33       ,1%  ,1/A CS03302FB19              R434            
Q_RES_0402LF-33       ,1%  ,1/A CS03302FB19              R435            
Q_RES_0402LF-33       ,1%  ,1/A CS03302FB19              R436            
Q_RES_0402LF-33       ,1%  ,1/A CS03302FB19              R437            
Q_RES_0402LF-33       ,1%  ,1/A CS03302FB19              R439            
Q_RES_0402LF-33       ,1%  ,1/A CS03302FB19              R440            
Q_RES_0402LF-33       ,1%  ,1/A CS03302FB19              R442            
Q_RES_0402LF-33       ,1%  ,1/A CS03302FB19              R443            
Q_RES_0402LF-33       ,1%  ,1/A CS03302FB19              R444            
Q_RES_0402LF-33       ,1%  ,1/A CS03302FB19              R448            
Q_RES_0402LF-33       ,1%  ,1/A CS03302FB19              R449            
Q_RES_0402LF-33       ,1%  ,1/A CS03302FB19              R458            
Q_RES_0402LF-33       ,1%  ,1/A CS03302FB19              R459            
Q_RES_0402LF-33       ,1%  ,1/A CS03302FB19              R460            
Q_RES_0402LF-33       ,1%  ,1/A CS03302FB19              R461            
Q_RES_0402LF-33       ,1%  ,1/A CS03302FB19              R462            
Q_RES_0402LF-33       ,1%  ,1/A CS03302FB19              R463            
Q_RES_0402LF-33       ,1%  ,1/A CS03302FB19              R465            
Q_RES_0402LF-33       ,1%  ,1/A CS03302FB19              R466            
Q_RES_0402LF-33       ,1%  ,1/A CS03302FB19              R468            
Q_RES_0402LF-33       ,1%  ,1/A CS03302FB19              R469            
Q_RES_0402LF-33       ,1%  ,1/A CS03302FB19              R470            
Q_RES_0402LF-33       ,1%  ,1/A CS03302FB19              R471            
Q_RES_0402LF-33       ,1%  ,1/A CS03302FB19              R472            
Q_RES_0402LF-33       ,1%  ,1/A CS03302FB19              R473            
Q_RES_0402LF-33       ,1%  ,1/A CS03302FB19              R474            
Q_RES_0402LF-33       ,1%  ,1/A CS03302FB19              R475            
Q_RES_0402LF-33       ,1%  ,1/A CS03302FB19              R476            
Q_RES_0402LF-33       ,1%  ,1/A CS03302FB19              R477            
Q_RES_0402LF-33       ,1%  ,1/A CS03302FB19              R478            
Q_RES_0402LF-33       ,1%  ,1/A CS03302FB19              R479            
Q_RES_0402LF-33       ,1%  ,1/A CS03302FB19              R480            
Q_RES_0402LF-33       ,1%  ,1/A CS03302FB19              R481            
Q_RES_0402LF-33       ,1%  ,1/A CS03302FB19              R482            
Q_RES_0402LF-33       ,1%  ,1/A CS03302FB19              R483            
Q_RES_0402LF-33       ,1%  ,1/A CS03302FB19              R484            
Q_RES_0402LF-33       ,1%  ,1/A CS03302FB19              R485            
Q_RES_0402LF-33       ,1%  ,1/A CS03302FB19              R486            
Q_RES_0402LF-33       ,1%  ,1/A CS03302FB19              R489            
Q_RES_0402LF-33       ,1%  ,1/A CS03302FB19              R491            
Q_RES_0402LF-33       ,1%  ,1/A CS03302FB19              R493            
Q_RES_0402LF-33       ,1%  ,1/A CS03302FB19              R494            
Q_RES_0402LF-33       ,1%  ,1/A CS03302FB19              R509            
Q_RES_0402LF-33       ,1%  ,1/A CS03302FB19              R510            
Q_RES_0402LF-33       ,1%  ,1/A CS03302FB19              R511            
Q_RES_0402LF-33       ,1%  ,1/A CS03302FB19              R512            
Q_RES_0402LF-33       ,1%  ,1/A CS03302FB19              R513            
Q_RES_0402LF-33       ,1%  ,1/A CS03302FB19              R514            
Q_RES_0402LF-33       ,1%  ,1/A CS03302FB19              R515            
Q_RES_0402LF-33       ,1%  ,1/A CS03302FB19              R516            
Q_RES_0402LF-33       ,1%  ,1/A CS03302FB19              R517            
Q_RES_0402LF-33       ,1%  ,1/A CS03302FB19              R518            
Q_RES_0402LF-33       ,1%  ,1/A CS03302FB19              R522            
Q_RES_0402LF-33       ,1%  ,1/A CS03302FB19              R524            
Q_RES_0402LF-33       ,1%  ,1/A CS03302FB19              R525            
Q_RES_0402LF-33       ,1%  ,1/A CS03302FB19              R526            
Q_RES_0402LF-33       ,1%  ,1/A CS03302FB19              R531            
Q_RES_0402LF-33       ,1%  ,1/A CS03302FB19              R533            
Q_RES_0402LF-33       ,1%  ,1/A CS03302FB19              R534            
Q_RES_0402LF-33       ,1%  ,1/A CS03302FB19              R535            
Q_RES_0402LF-33       ,1%  ,1/A CS03302FB19              R536            
Q_RES_0402LF-33       ,1%  ,1/A CS03302FB19              R537            
Q_RES_0402LF-33       ,1%  ,1/A CS03302FB19              R540            
Q_RES_0402LF-33       ,1%  ,1/A CS03302FB19              R541            
Q_RES_0402LF-33       ,1%  ,1/A CS03302FB19              R543            
Q_RES_0402LF-33       ,1%  ,1/A CS03302FB19              R544            
Q_RES_0402LF-33       ,1%  ,1/A CS03302FB19              R545            
Q_RES_0402LF-33       ,1%  ,1/A CS03302FB19              R546            
Q_RES_0402LF-33       ,1%  ,1/A CS03302FB19              R547            
Q_RES_0402LF-33       ,1%  ,1/A CS03302FB19              R548            
Q_RES_0402LF-33       ,1%  ,1/A CS03302FB19              R549            
Q_RES_0402LF-33       ,1%  ,1/A CS03302FB19              R550            
Q_RES_0402LF-33       ,1%  ,1/A CS03302FB19              R551            
Q_RES_0402LF-33       ,1%  ,1/A CS03302FB19              R552            
Q_RES_0402LF-33       ,1%  ,1/A CS03302FB19              R553            
Q_RES_0402LF-33       ,1%  ,1/A CS03302FB19              R554            
Q_RES_0402LF-33       ,1%  ,1/A CS03302FB19              R567            
Q_RES_0402LF-33       ,1%  ,1/A CS03302FB19              R570            
Q_RES_0402LF-33       ,1%  ,1/A CS03302FB19              R580            
Q_RES_0402LF-33       ,1%  ,1/A CS03302FB19              R582            
Q_RES_0402LF-33       ,1%  ,1/A CS03302FB19              R583            
Q_RES_0402LF-33       ,1%  ,1/A CS03302FB19              R584            
Q_RES_0402LF-33       ,1%  ,1/A CS03302FB19              R589            
Q_RES_0402LF-33       ,1%  ,1/A CS03302FB19              R590            
Q_RES_0402LF-33       ,1%  ,1/A CS03302FB19              R594            
Q_RES_0402LF-33       ,1%  ,1/A CS03302FB19              R635            
Q_RES_0402LF-33       ,1%  ,1/A CS03302FB19              R638            
Q_RES_0402LF-33       ,1%  ,1/A CS03302FB19              R639            
Q_RES_0402LF-33       ,1%  ,1/A CS03302FB19              R690            
Q_RES_0402LF-33       ,1%  ,1/A CS03302FB19              R691            
Q_RES_0402LF-33       ,1%  ,1/A CS03302FB19              R704            
Q_RES_0402LF-33       ,1%  ,1/A CS03302FB19              R705            
Q_RES_0402LF-33       ,1%  ,1/A CS03302FB19              R713            
Q_RES_0402LF-33       ,1%  ,1/A CS03302FB19              R718            
Q_RES_0402LF-33       ,1%  ,1/A CS03302FB19              R724            
Q_RES_0402LF-33       ,1%  ,1/A CS03302FB19              R725            
Q_RES_0402LF-33       ,1%  ,1/A CS03302FB19              R759            
Q_RES_0402LF-33       ,1%  ,1/A CS03302FB19              R760            
Q_RES_0402LF-33       ,1%  ,1/A CS03302FB19              R761            
Q_RES_0402LF-33       ,1%  ,1/A CS03302FB19              R762            
Q_RES_0402LF-33       ,1%  ,1/A CS03302FB19              R763            
Q_RES_0402LF-33       ,1%  ,1/A CS03302FB19              R767            
Q_RES_0402LF-33       ,1%  ,1/A CS03302FB19              R769            
Q_RES_0402LF-33       ,1%  ,1/A CS03302FB19              R773            
Q_RES_0402LF-33       ,1%  ,1/A CS03302FB19              R799            
Q_RES_0402LF-33       ,1%  ,1/A CS03302FB19              R801            
Q_RES_0402LF-33       ,1%  ,1/A CS03302FB19              R802            
Q_RES_0402LF-33       ,1%  ,1/A CS03302FB19              R803            
Q_RES_0402LF-33       ,1%  ,1/A CS03302FB19              R804            
Q_RES_0402LF-33       ,1%  ,1/A CS03302FB19              R807            
Q_RES_0402LF-33       ,1%  ,1/A CS03302FB19              R812            
Q_RES_0402LF-33       ,1%  ,1/A CS03302FB19              R813            
Q_RES_0402LF-33       ,1%  ,1/A CS03302FB19              R824            
Q_RES_0402LF-33       ,1%  ,1/A CS03302FB19              R825            
Q_RES_0402LF-33       ,1%  ,1/A CS03302FB19              R833            
Q_RES_0402LF-33       ,1%  ,1/A CS03302FB19              R836            
Q_RES_0402LF-33       ,1%  ,1/A CS03302FB19              R840            
Q_RES_0402LF-33       ,1%  ,1/A CS03302FB19              R841            
Q_RES_0402LF-33       ,1%  ,1/A CS03302FB19              R852            
Q_RES_0402LF-33       ,1%  ,1/A CS03302FB19              R859            
Q_RES_0402LF-33       ,1%  ,1/A CS03302FB19              R860            
Q_RES_0402LF-33       ,1%  ,1/A CS03302FB19              R861            
Q_RES_0402LF-33       ,1%  ,1/A CS03302FB19              R862            
Q_RES_0402LF-33       ,1%  ,1/A CS03302FB19              R863            
Q_RES_0402LF-33       ,1%  ,1/A CS03302FB19              R864            

----------------

Q_RES_0402LF-33       ,1%  ,1/B CS03302FB19              R33             
Q_RES_0402LF-33       ,1%  ,1/B CS03302FB19              R47             
Q_RES_0402LF-33       ,1%  ,1/B CS03302FB19              R48             
Q_RES_0402LF-33       ,1%  ,1/B CS03302FB19              R80             
Q_RES_0402LF-33       ,1%  ,1/B CS03302FB19              R107            
Q_RES_0402LF-33       ,1%  ,1/B CS03302FB19              R126            
Q_RES_0402LF-33       ,1%  ,1/B CS03302FB19              R136            
Q_RES_0402LF-33       ,1%  ,1/B CS03302FB19              R532            
Q_RES_0402LF-33       ,1%  ,1/B CS03302FB19              R561            
Q_RES_0402LF-33       ,1%  ,1/B CS03302FB19              R562            
Q_RES_0402LF-33       ,1%  ,1/B CS03302FB19              R647            
Q_RES_0402LF-33       ,1%  ,1/B CS03302FB19              R648            
Q_RES_0402LF-33       ,1%  ,1/B CS03302FB19              R649            
Q_RES_0402LF-33       ,1%  ,1/B CS03302FB19              R650            
Q_RES_0402LF-33       ,1%  ,1/B CS03302FB19              R651            
Q_RES_0402LF-33       ,1%  ,1/B CS03302FB19              R652            
Q_RES_0402LF-33       ,1%  ,1/B CS03302FB19              R653            
Q_RES_0402LF-33       ,1%  ,1/B CS03302FB19              R654            
Q_RES_0402LF-33       ,1%  ,1/B CS03302FB19              R677            
Q_RES_0402LF-33       ,1%  ,1/B CS03302FB19              R678            
Q_RES_0402LF-33       ,1%  ,1/B CS03302FB19              R679            
Q_RES_0402LF-33       ,1%  ,1/B CS03302FB19              R680            
Q_RES_0402LF-33       ,1%  ,1/B CS03302FB19              R681            
Q_RES_0402LF-33       ,1%  ,1/B CS03302FB19              R682            
Q_RES_0402LF-33       ,1%  ,1/B CS03302FB19              R688            
Q_RES_0402LF-33       ,1%  ,1/B CS03302FB19              R689            
Q_RES_0402LF-33       ,1%  ,1/B CS03302FB19              R765            
Q_RES_0402LF-33       ,1%  ,1/B CS03302FB19              R766            
Q_RES_0402LF-33       ,1%  ,1/B CS03302FB19              R837            

----------------

Q_RES_0402LF-330,1%,1/16W,CHIPA CS13302FB11              R167            

----------------

Q_RES_0402LF-4.7K,1%,1/16W,CHIA CS24702FB10              R11             
Q_RES_0402LF-4.7K,1%,1/16W,CHIA CS24702FB10              R31             
Q_RES_0402LF-4.7K,1%,1/16W,CHIA CS24702FB10              R32             
Q_RES_0402LF-4.7K,1%,1/16W,CHIA CS24702FB10              R67             
Q_RES_0402LF-4.7K,1%,1/16W,CHIA CS24702FB10              R291            
Q_RES_0402LF-4.7K,1%,1/16W,CHIA CS24702FB10              R298            
Q_RES_0402LF-4.7K,1%,1/16W,CHIA CS24702FB10              R299            
Q_RES_0402LF-4.7K,1%,1/16W,CHIA CS24702FB10              R307            
Q_RES_0402LF-4.7K,1%,1/16W,CHIA CS24702FB10              R309            
Q_RES_0402LF-4.7K,1%,1/16W,CHIA CS24702FB10              R311            
Q_RES_0402LF-4.7K,1%,1/16W,CHIA CS24702FB10              R376            
Q_RES_0402LF-4.7K,1%,1/16W,CHIA CS24702FB10              R387            
Q_RES_0402LF-4.7K,1%,1/16W,CHIA CS24702FB10              R389            
Q_RES_0402LF-4.7K,1%,1/16W,CHIA CS24702FB10              R488            
Q_RES_0402LF-4.7K,1%,1/16W,CHIA CS24702FB10              R490            
Q_RES_0402LF-4.7K,1%,1/16W,CHIA CS24702FB10              R492            
Q_RES_0402LF-4.7K,1%,1/16W,CHIA CS24702FB10              R502            
Q_RES_0402LF-4.7K,1%,1/16W,CHIA CS24702FB10              R555            
Q_RES_0402LF-4.7K,1%,1/16W,CHIA CS24702FB10              R557            
Q_RES_0402LF-4.7K,1%,1/16W,CHIA CS24702FB10              R559            
Q_RES_0402LF-4.7K,1%,1/16W,CHIA CS24702FB10              R563            
Q_RES_0402LF-4.7K,1%,1/16W,CHIA CS24702FB10              R623            
Q_RES_0402LF-4.7K,1%,1/16W,CHIA CS24702FB10              R625            

----------------

Q_RES_0402LF-4.7K,1%,1/16W,EMPA CS24702FB10              R72             
Q_RES_0402LF-4.7K,1%,1/16W,EMPA CS24702FB10              R229            
Q_RES_0402LF-4.7K,1%,1/16W,EMPA CS24702FB10              R284            
Q_RES_0402LF-4.7K,1%,1/16W,EMPA CS24702FB10              R308            
Q_RES_0402LF-4.7K,1%,1/16W,EMPA CS24702FB10              R310            
Q_RES_0402LF-4.7K,1%,1/16W,EMPA CS24702FB10              R312            
Q_RES_0402LF-4.7K,1%,1/16W,EMPA CS24702FB10              R388            
Q_RES_0402LF-4.7K,1%,1/16W,EMPA CS24702FB10              R390            
Q_RES_0402LF-4.7K,1%,1/16W,EMPA CS24702FB10              R487            
Q_RES_0402LF-4.7K,1%,1/16W,EMPA CS24702FB10              R496            
Q_RES_0402LF-4.7K,1%,1/16W,EMPA CS24702FB10              R556            
Q_RES_0402LF-4.7K,1%,1/16W,EMPA CS24702FB10              R558            
Q_RES_0402LF-4.7K,1%,1/16W,EMPA CS24702FB10              R560            

----------------

Q_RES_0402LF-4.7K,5%,1/16W,CHIA CS24702JB38              R9              
Q_RES_0402LF-4.7K,5%,1/16W,CHIA CS24702JB38              R12             
Q_RES_0402LF-4.7K,5%,1/16W,CHIA CS24702JB38              R34             
Q_RES_0402LF-4.7K,5%,1/16W,CHIA CS24702JB38              R44             
Q_RES_0402LF-4.7K,5%,1/16W,CHIA CS24702JB38              R45             
Q_RES_0402LF-4.7K,5%,1/16W,CHIA CS24702JB38              R55             
Q_RES_0402LF-4.7K,5%,1/16W,CHIA CS24702JB38              R56             
Q_RES_0402LF-4.7K,5%,1/16W,CHIA CS24702JB38              R57             
Q_RES_0402LF-4.7K,5%,1/16W,CHIA CS24702JB38              R58             
Q_RES_0402LF-4.7K,5%,1/16W,CHIA CS24702JB38              R61             
Q_RES_0402LF-4.7K,5%,1/16W,CHIA CS24702JB38              R62             
Q_RES_0402LF-4.7K,5%,1/16W,CHIA CS24702JB38              R68             
Q_RES_0402LF-4.7K,5%,1/16W,CHIA CS24702JB38              R69             
Q_RES_0402LF-4.7K,5%,1/16W,CHIA CS24702JB38              R70             
Q_RES_0402LF-4.7K,5%,1/16W,CHIA CS24702JB38              R81             
Q_RES_0402LF-4.7K,5%,1/16W,CHIA CS24702JB38              R101            
Q_RES_0402LF-4.7K,5%,1/16W,CHIA CS24702JB38              R103            
Q_RES_0402LF-4.7K,5%,1/16W,CHIA CS24702JB38              R115            
Q_RES_0402LF-4.7K,5%,1/16W,CHIA CS24702JB38              R116            
Q_RES_0402LF-4.7K,5%,1/16W,CHIA CS24702JB38              R117            
Q_RES_0402LF-4.7K,5%,1/16W,CHIA CS24702JB38              R140            
Q_RES_0402LF-4.7K,5%,1/16W,CHIA CS24702JB38              R145            
Q_RES_0402LF-4.7K,5%,1/16W,CHIA CS24702JB38              R149            
Q_RES_0402LF-4.7K,5%,1/16W,CHIA CS24702JB38              R161            
Q_RES_0402LF-4.7K,5%,1/16W,CHIA CS24702JB38              R163            
Q_RES_0402LF-4.7K,5%,1/16W,CHIA CS24702JB38              R169            
Q_RES_0402LF-4.7K,5%,1/16W,CHIA CS24702JB38              R188            
Q_RES_0402LF-4.7K,5%,1/16W,CHIA CS24702JB38              R189            
Q_RES_0402LF-4.7K,5%,1/16W,CHIA CS24702JB38              R190            
Q_RES_0402LF-4.7K,5%,1/16W,CHIA CS24702JB38              R191            
Q_RES_0402LF-4.7K,5%,1/16W,CHIA CS24702JB38              R194            
Q_RES_0402LF-4.7K,5%,1/16W,CHIA CS24702JB38              R195            
Q_RES_0402LF-4.7K,5%,1/16W,CHIA CS24702JB38              R196            
Q_RES_0402LF-4.7K,5%,1/16W,CHIA CS24702JB38              R197            
Q_RES_0402LF-4.7K,5%,1/16W,CHIA CS24702JB38              R212            
Q_RES_0402LF-4.7K,5%,1/16W,CHIA CS24702JB38              R238            
Q_RES_0402LF-4.7K,5%,1/16W,CHIA CS24702JB38              R239            
Q_RES_0402LF-4.7K,5%,1/16W,CHIA CS24702JB38              R240            
Q_RES_0402LF-4.7K,5%,1/16W,CHIA CS24702JB38              R241            
Q_RES_0402LF-4.7K,5%,1/16W,CHIA CS24702JB38              R244            
Q_RES_0402LF-4.7K,5%,1/16W,CHIA CS24702JB38              R245            
Q_RES_0402LF-4.7K,5%,1/16W,CHIA CS24702JB38              R246            
Q_RES_0402LF-4.7K,5%,1/16W,CHIA CS24702JB38              R247            
Q_RES_0402LF-4.7K,5%,1/16W,CHIA CS24702JB38              R248            
Q_RES_0402LF-4.7K,5%,1/16W,CHIA CS24702JB38              R249            
Q_RES_0402LF-4.7K,5%,1/16W,CHIA CS24702JB38              R250            
Q_RES_0402LF-4.7K,5%,1/16W,CHIA CS24702JB38              R251            
Q_RES_0402LF-4.7K,5%,1/16W,CHIA CS24702JB38              R252            
Q_RES_0402LF-4.7K,5%,1/16W,CHIA CS24702JB38              R253            
Q_RES_0402LF-4.7K,5%,1/16W,CHIA CS24702JB38              R254            
Q_RES_0402LF-4.7K,5%,1/16W,CHIA CS24702JB38              R255            
Q_RES_0402LF-4.7K,5%,1/16W,CHIA CS24702JB38              R256            
Q_RES_0402LF-4.7K,5%,1/16W,CHIA CS24702JB38              R257            
Q_RES_0402LF-4.7K,5%,1/16W,CHIA CS24702JB38              R258            
Q_RES_0402LF-4.7K,5%,1/16W,CHIA CS24702JB38              R259            
Q_RES_0402LF-4.7K,5%,1/16W,CHIA CS24702JB38              R260            
Q_RES_0402LF-4.7K,5%,1/16W,CHIA CS24702JB38              R261            
Q_RES_0402LF-4.7K,5%,1/16W,CHIA CS24702JB38              R262            
Q_RES_0402LF-4.7K,5%,1/16W,CHIA CS24702JB38              R264            
Q_RES_0402LF-4.7K,5%,1/16W,CHIA CS24702JB38              R265            
Q_RES_0402LF-4.7K,5%,1/16W,CHIA CS24702JB38              R268            
Q_RES_0402LF-4.7K,5%,1/16W,CHIA CS24702JB38              R269            
Q_RES_0402LF-4.7K,5%,1/16W,CHIA CS24702JB38              R407            
Q_RES_0402LF-4.7K,5%,1/16W,CHIA CS24702JB38              R416            
Q_RES_0402LF-4.7K,5%,1/16W,CHIA CS24702JB38              R422            
Q_RES_0402LF-4.7K,5%,1/16W,CHIA CS24702JB38              R428            
Q_RES_0402LF-4.7K,5%,1/16W,CHIA CS24702JB38              R429            
Q_RES_0402LF-4.7K,5%,1/16W,CHIA CS24702JB38              R430            
Q_RES_0402LF-4.7K,5%,1/16W,CHIA CS24702JB38              R438            
Q_RES_0402LF-4.7K,5%,1/16W,CHIA CS24702JB38              R441            
Q_RES_0402LF-4.7K,5%,1/16W,CHIA CS24702JB38              R446            
Q_RES_0402LF-4.7K,5%,1/16W,CHIA CS24702JB38              R452            
Q_RES_0402LF-4.7K,5%,1/16W,CHIA CS24702JB38              R521            
Q_RES_0402LF-4.7K,5%,1/16W,CHIA CS24702JB38              R581            
Q_RES_0402LF-4.7K,5%,1/16W,CHIA CS24702JB38              R586            
Q_RES_0402LF-4.7K,5%,1/16W,CHIA CS24702JB38              R587            
Q_RES_0402LF-4.7K,5%,1/16W,CHIA CS24702JB38              R588            
Q_RES_0402LF-4.7K,5%,1/16W,CHIA CS24702JB38              R591            
Q_RES_0402LF-4.7K,5%,1/16W,CHIA CS24702JB38              R592            
Q_RES_0402LF-4.7K,5%,1/16W,CHIA CS24702JB38              R593            
Q_RES_0402LF-4.7K,5%,1/16W,CHIA CS24702JB38              R595            
Q_RES_0402LF-4.7K,5%,1/16W,CHIA CS24702JB38              R596            
Q_RES_0402LF-4.7K,5%,1/16W,CHIA CS24702JB38              R605            
Q_RES_0402LF-4.7K,5%,1/16W,CHIA CS24702JB38              R606            
Q_RES_0402LF-4.7K,5%,1/16W,CHIA CS24702JB38              R607            
Q_RES_0402LF-4.7K,5%,1/16W,CHIA CS24702JB38              R608            
Q_RES_0402LF-4.7K,5%,1/16W,CHIA CS24702JB38              R609            
Q_RES_0402LF-4.7K,5%,1/16W,CHIA CS24702JB38              R610            
Q_RES_0402LF-4.7K,5%,1/16W,CHIA CS24702JB38              R611            
Q_RES_0402LF-4.7K,5%,1/16W,CHIA CS24702JB38              R612            
Q_RES_0402LF-4.7K,5%,1/16W,CHIA CS24702JB38              R613            
Q_RES_0402LF-4.7K,5%,1/16W,CHIA CS24702JB38              R615            
Q_RES_0402LF-4.7K,5%,1/16W,CHIA CS24702JB38              R617            
Q_RES_0402LF-4.7K,5%,1/16W,CHIA CS24702JB38              R619            
Q_RES_0402LF-4.7K,5%,1/16W,CHIA CS24702JB38              R621            
Q_RES_0402LF-4.7K,5%,1/16W,CHIA CS24702JB38              R622            
Q_RES_0402LF-4.7K,5%,1/16W,CHIA CS24702JB38              R624            
Q_RES_0402LF-4.7K,5%,1/16W,CHIA CS24702JB38              R626            
Q_RES_0402LF-4.7K,5%,1/16W,CHIA CS24702JB38              R627            
Q_RES_0402LF-4.7K,5%,1/16W,CHIA CS24702JB38              R632            
Q_RES_0402LF-4.7K,5%,1/16W,CHIA CS24702JB38              R640            
Q_RES_0402LF-4.7K,5%,1/16W,CHIA CS24702JB38              R641            
Q_RES_0402LF-4.7K,5%,1/16W,CHIA CS24702JB38              R683            
Q_RES_0402LF-4.7K,5%,1/16W,CHIA CS24702JB38              R692            
Q_RES_0402LF-4.7K,5%,1/16W,CHIA CS24702JB38              R706            
Q_RES_0402LF-4.7K,5%,1/16W,CHIA CS24702JB38              R717            
Q_RES_0402LF-4.7K,5%,1/16W,CHIA CS24702JB38              R774            
Q_RES_0402LF-4.7K,5%,1/16W,CHIA CS24702JB38              R806            
Q_RES_0402LF-4.7K,5%,1/16W,CHIA CS24702JB38              R828            
Q_RES_0402LF-4.7K,5%,1/16W,CHIA CS24702JB38              R842            
Q_RES_0402LF-4.7K,5%,1/16W,CHIA CS24702JB38              R843            
Q_RES_0402LF-4.7K,5%,1/16W,CHIA CS24702JB38              R844            
Q_RES_0402LF-4.7K,5%,1/16W,CHIA CS24702JB38              R848            
Q_RES_0402LF-4.7K,5%,1/16W,CHIA CS24702JB38              R851            

----------------

Q_RES_0402LF-4.7K,5%,1/16W,EMPA CS24702JB38              R13             
Q_RES_0402LF-4.7K,5%,1/16W,EMPA CS24702JB38              R14             
Q_RES_0402LF-4.7K,5%,1/16W,EMPA CS24702JB38              R38             
Q_RES_0402LF-4.7K,5%,1/16W,EMPA CS24702JB38              R266            
Q_RES_0402LF-4.7K,5%,1/16W,EMPA CS24702JB38              R267            
Q_RES_0402LF-4.7K,5%,1/16W,EMPA CS24702JB38              R414            
Q_RES_0402LF-4.7K,5%,1/16W,EMPA CS24702JB38              R418            
Q_RES_0402LF-4.7K,5%,1/16W,EMPA CS24702JB38              R455            
Q_RES_0402LF-4.7K,5%,1/16W,EMPA CS24702JB38              R686            
Q_RES_0402LF-4.7K,5%,1/16W,EMPA CS24702JB38              R687            
Q_RES_0402LF-4.7K,5%,1/16W,EMPA CS24702JB38              R699            
Q_RES_0402LF-4.7K,5%,1/16W,EMPA CS24702JB38              R821            
Q_RES_0402LF-4.7K,5%,1/16W,EMPA CS24702JB38              R845            
Q_RES_0402LF-4.7K,5%,1/16W,EMPA CS24702JB38              R846            
Q_RES_0402LF-4.7K,5%,1/16W,EMPA CS24702JB38              R870            

----------------

Q_RES_0402LF-470K,1%,1/16W,CHIA CS44702FB13              R313            

----------------

Q_RES_0402LF-47K,1%,1/16W,CHIPA CS34702FB11              R290            

----------------

Q_RES_0402LF-47K,5%,1/16W,EMPTA CS34702JB21              R206            

----------------

Q_RES_0402LF-49.9     ,1%  ,1/A CS04992FB31              R108            
Q_RES_0402LF-49.9     ,1%  ,1/A CS04992FB31              R192            

----------------

Q_RES_0402LF-499,1%,1/16W,CHIPA CS14992FB24              R287            

----------------

Q_RES_0402LF-5.1,5%,1/16W,CHIPA CS-5102JB03              PR539           
Q_RES_0402LF-5.1,5%,1/16W,CHIPA CS-5102JB03              PR541           

----------------

Q_RES_0402LF-5.36K,1%,1/16W,CHA CS25362FB15              R787            

----------------

Q_RES_0402LF-51.1K,1%,1/16W,CHA CS35112FB17              PR241           

----------------

Q_RES_0402LF-56K,1%,1/16W,CHIPA CS35602FB11              PR534           

----------------

Q_RES_0402LF-60.4,1%,1/16W,CHIA CS06042FB14              R7              
Q_RES_0402LF-60.4,1%,1/16W,CHIA CS06042FB14              R8              

----------------

Q_RES_0402LF-60.4K,1%,1/16W,CHA CS36042FB10              PR532           

----------------

Q_RES_0402LF-665,1%,1/16W,CHIPA CS16652FB04              R793            

----------------

Q_RES_0402LF-681K,1%,1/16W,CHIA CS46812FB00              PR521           

----------------

Q_RES_0402LF-750,1%,1/16W,CHIPA CS17502FB19              R597            
Q_RES_0402LF-750,1%,1/16W,CHIPA CS17502FB19              R598            
Q_RES_0402LF-750,1%,1/16W,CHIPA CS17502FB19              R599            
Q_RES_0402LF-750,1%,1/16W,CHIPA CS17502FB19              R600            
Q_RES_0402LF-750,1%,1/16W,CHIPA CS17502FB19              R601            
Q_RES_0402LF-750,1%,1/16W,CHIPA CS17502FB19              R602            
Q_RES_0402LF-750,1%,1/16W,CHIPA CS17502FB19              R603            
Q_RES_0402LF-750,1%,1/16W,CHIPA CS17502FB19              R604            

----------------

Q_RES_0402LF-8.2K     ,5%  ,1/A CS28202JB14              R504            
Q_RES_0402LF-8.2K     ,5%  ,1/A CS28202JB14              R768            
Q_RES_0402LF-8.2K     ,5%  ,1/A CS28202JB14              R839            

----------------

Q_RES_0402LF-8.66K,1%,1/16W,CHA CS28662FB14              PR276           

----------------

Q_RES_0402LF-91K,1%,1/16W,CHIPA CS39102FB05              PR527           

----------------

Q_RES_0603-0,5%,1/10W,EMPTY,TMA CS00003J951              R27             

----------------

Q_XTAL_4P_13BI_24GND-25MHZ,SMLA BG625000802              Y1              

----------------

RT9059GQW-RT9059GQW,SMLF,IC,ALA AL009059000              PU39            
RT9059GQW-RT9059GQW,SMLF,IC,ALA AL009059000              PU40            

----------------

SCHOTTKY_AC-RB161SS-20T2R,SMLFA BC0161SS000              D16             

----------------

SCHOTTKY_AC-SS0530,SMLF,EMPTY,A BCSS0530Z00              D9              

----------------

SCHOTTKY_AC-SS0530,SMLF,IC,BCSA BCSS0530Z00              D11             

----------------

SCONN11_9192031111LF-SCONN11_9A DFHS11FS009              J5              
SCONN11_9192031111LF-SCONN11_9A DFHS11FS009              J10             

----------------

SCONN13_502240130C001-SCONN13_A DFHD13MR071              J8              

----------------

SCONN14_RS6QU0001-SCONN14_RS6-A DFTJ14FR046              J1              

----------------

SCONN16_ACASPI006P06-SCONN16_AA DG016000006              J40             
SCONN16_ACASPI006P06-SCONN16_AA DG016000006              J121            

----------------

SCONN20_3VM11207D7307H-SCONN20A DFHS20FR233              J3              

----------------

SCONN5_2UB2141000111F-SCONN5_2A DFHS05FR105              J4              

----------------

SN74LVC1G07DBVR_SMLF-SN74LVC1GA AL1G0007024              U23             

----------------

SN74LVC1G07DCKR-SN74LVC1G07DCKA AL1G0007016              U13             

----------------

SN74LVC1G3157DCKR-SN74LVC1G315A AL1G3157001              U2              
SN74LVC1G3157DCKR-SN74LVC1G315A AL1G3157001              U3              

----------------

SN74LVC2G07DCKR_SMLF-SN74LVC2GA AL002G07006              U6              
SN74LVC2G07DCKR_SMLF-SN74LVC2GA AL002G07006              U24             

----------------

SW2S_TA31E2KQTR-SW2S_TA3-1E2K-A DHP01E2KQ00              SW6             
SW2S_TA31E2KQTR-SW2S_TA3-1E2K-A DHP01E2KQ00              SW7             

----------------

SW4S_DHNF02FTVTR-SW4S_DHNF-02FA DHP00002F00              SW1             
SW4S_DHNF02FTVTR-SW4S_DHNF-02FA DHP00002F00              SW2             
SW4S_DHNF02FTVTR-SW4S_DHNF-02FA DHP00002F00              SW3             

----------------

TMP75AIDGKR-TMP75AIDGKR,SMLF,IA AL0000750E3              U4              

----------------

TPD2EUSB30DRTR_SMLF-TPD2EUSB30A AL2EUSB3000              U18             

----------------

TPD4E001DBVR-TPD4E001DBVR,SMLFA BC01DBVR000              U16             
TPD4E001DBVR-TPD4E001DBVR,SMLFA BC01DBVR000              U34             
TPD4E001DBVR-TPD4E001DBVR,SMLFA BC01DBVR000              U35             

----------------

TPD4E001DBVR-TPD4E001DBVR,SMLFB BC01DBVR000              U8              
TPD4E001DBVR-TPD4E001DBVR,SMLFB BC01DBVR000              U9              

----------------

TPS22965DSGR-TPS22965DSGR,SMLFA AL022965000              U15             

----------------

TPS2553DBVR1-TPS2553DBVR-1,SMLA AL002553002              U10             

----------------

TPS3808G33DBVR-TPS3808G33DBVR,A AL380833000              U43             

----------------

END STUFF LIST
